FILE_TYPE = MACRO_DRAWING;
SET COLOR_WIRE YELLOW;
SET COLOR_PROP MONO;
SET COLOR_DOT WHITE;
SET COLOR_ARC YELLOW;
SET COLOR_BODY GREEN;
SET COLOR_NOTE MONO;
SET PROP_DISPLAY VALUE;
SET PAGE_NUMBER P111;
FORCEADD CAP_A..1
R 1
(2750 1900);
FORCEPROP 1 LAST VALUE 0.1UF
J 0
(2500 1950);
DISPLAY 0.617021 (2500 1950);
PAINT SKYBLUE (2500 1950);
FORCEPROP 1 LAST LOCATION C9A2
J 0
(2675 2000);
DISPLAY 0.617021 (2675 2000);
PAINT AQUA (2675 2000);
FORCEPROP 1 LASTPIN (2650 1900) $PN 1
J 0
(2670 1910);
DISPLAY 0.617021 (2670 1910);
PAINT WHITE (2670 1910);
FORCEPROP 1 LAST VOLTAGE 16V
J 0
(2650 1950);
DISPLAY 0.617021 (2650 1950);
PAINT SKYBLUE (2650 1950);
FORCEPROP 1 LAST PART_NUMBER A36096-030
J 0
(2650 1825);
DISPLAY 0.617021 (2650 1825);
PAINT BLUE (2650 1825);
FORCEPROP 1 LAST TOLERANCE 10%
J 0
(2775 1950);
DISPLAY 0.617021 (2775 1950);
PAINT SKYBLUE (2775 1950);
FORCEPROP 1 LASTPIN (2850 1900) $PN 2
J 0
(2795 1910);
DISPLAY 0.617021 (2795 1910);
PAINT WHITE (2795 1910);
FORCEPROP 1 LAST MATERIAL X7R
J 0
(2900 1950);
DISPLAY 0.617021 (2900 1950);
PAINT SKYBLUE (2900 1950);
FORCEPROP 1 LAST PACK_TYPE 0402V
J 0
(3000 1950);
DISPLAY 0.617021 (3000 1950);
PAINT SKYBLUE (3000 1950);
FORCEPROP 1 LAST PATH I10
R 1
J 0
(2600 1950);
DISPLAY 0.978723 (2600 1950);
PAINT WHITE (2600 1950);
DISPLAY INVISIBLE (2600 1950);
FORCEPROP 2 LAST SEC_TYPE 0402V
R 1
J 0
(2750 2025);
DISPLAY 1.659574 (2750 2025);
PAINT ORANGE (2750 2025);
DISPLAY INVISIBLE (2750 2025);
FORCEPROP 2 LAST CDS_LIB dev_discrete
J 0
(2750 1900);
PAINT ORANGE (2750 1900);
DISPLAY INVISIBLE (2750 1900);
FORCEPROP 2 LAST CDS_LOCATION C9A2
J 0
(2750 1975);
DISPLAY 0.617021 (2750 1975);
PAINT AQUA (2750 1975);
DISPLAY INVISIBLE (2750 1975);
FORCEPROP 2 LAST CDS_SEC 1
R 1
J 0
(2750 2025);
PAINT ORANGE (2750 2025);
DISPLAY INVISIBLE (2750 2025);
FORCEPROP 2 LAST ROOM DEBUG
J 0
(2750 2025);
DISPLAY 1.617021 (2750 2025);
PAINT WHITE (2750 2025);
DISPLAY INVISIBLE (2750 2025);
FORCEPROP 2 LAST BOM_COST DEBUG
J 0
(2750 2025);
DISPLAY 1.617021 (2750 2025);
PAINT WHITE (2750 2025);
DISPLAY INVISIBLE (2750 2025);
FORCEPROP 2 LAST SEC 1
J 0
(2750 2025);
DISPLAY 1.510638 (2750 2025);
PAINT MONO (2750 2025);
DISPLAY INVISIBLE (2750 2025);
FORCEADD RES..1
(2725 1700);
FORCEPROP 1 LAST VALUE 1.00K
J 2
(2575 1650);
DISPLAY 0.617021 (2575 1650);
PAINT SKYBLUE (2575 1650);
FORCEPROP 1 LASTPIN (2625 1700) $PN 1
J 0
(2637 1712);
DISPLAY 0.617021 (2637 1712);
PAINT WHITE (2637 1712);
FORCEPROP 1 LAST WATTAGE 1/16W
J 2
(2725 1650);
DISPLAY 0.617021 (2725 1650);
PAINT SKYBLUE (2725 1650);
FORCEPROP 1 LAST LOCATION R9A14
J 0
(2675 1750);
DISPLAY 0.617021 (2675 1750);
PAINT AQUA (2675 1750);
FORCEPROP 1 LAST TOLERANCE 1%
J 0
(2775 1650);
DISPLAY 0.617021 (2775 1650);
PAINT SKYBLUE (2775 1650);
FORCEPROP 1 LASTPIN (2825 1700) $PN 2
J 0
(2787 1712);
DISPLAY 0.617021 (2787 1712);
PAINT WHITE (2787 1712);
FORCEPROP 1 LAST PACK_TYPE 0402
J 0
(2875 1650);
DISPLAY 0.617021 (2875 1650);
PAINT SKYBLUE (2875 1650);
FORCEPROP 1 LAST PART_NUMBER G21796-026
J 0
(2850 1725);
DISPLAY 0.617021 (2850 1725);
PAINT BLUE (2850 1725);
FORCEPROP 1 LAST MATERIAL CHIP
J 0
(3000 1650);
DISPLAY 0.617021 (3000 1650);
PAINT SKYBLUE (3000 1650);
FORCEPROP 2 LAST CDS_LOCATION R9A14
J 0
(2675 1750);
DISPLAY 0.617021 (2675 1750);
PAINT AQUA (2675 1750);
DISPLAY INVISIBLE (2675 1750);
FORCEPROP 2 LAST CDS_LIB mstr_discrete
J 0
(2725 1700);
DISPLAY 2.212766 (2725 1700);
PAINT ORANGE (2725 1700);
DISPLAY INVISIBLE (2725 1700);
FORCEPROP 1 LAST PATH I11
J 0
(2675 1850);
DISPLAY 0.978723 (2675 1850);
PAINT WHITE (2675 1850);
DISPLAY INVISIBLE (2675 1850);
FORCEPROP 2 LAST SEC 1
J 0
(2675 1900);
DISPLAY 1.510638 (2675 1900);
PAINT MONO (2675 1900);
DISPLAY INVISIBLE (2675 1900);
FORCEPROP 2 LAST BOM_COST DEBUG
J 0
(2675 1800);
DISPLAY 1.617021 (2675 1800);
PAINT WHITE (2675 1800);
DISPLAY INVISIBLE (2675 1800);
FORCEPROP 2 LAST SEC_TYPE 0402
J 0
(2675 1800);
DISPLAY 1.659574 (2675 1800);
PAINT ORANGE (2675 1800);
DISPLAY INVISIBLE (2675 1800);
FORCEPROP 2 LAST ROOM DEBUG
J 0
(2675 1850);
DISPLAY 1.617021 (2675 1850);
PAINT WHITE (2675 1850);
DISPLAY INVISIBLE (2675 1850);
FORCEADD CAP_A..1
R 1
(2800 1450);
FORCEPROP 1 LAST VALUE 0.1UF
J 0
(2450 1475);
DISPLAY 0.617021 (2450 1475);
PAINT SKYBLUE (2450 1475);
FORCEPROP 1 LAST VOLTAGE 16V
J 0
(2550 1475);
DISPLAY 0.617021 (2550 1475);
PAINT SKYBLUE (2550 1475);
FORCEPROP 1 LAST TOLERANCE 10%
J 0
(2625 1475);
DISPLAY 0.617021 (2625 1475);
PAINT SKYBLUE (2625 1475);
FORCEPROP 1 LASTPIN (2700 1450) $PN 1
J 0
(2720 1460);
DISPLAY 0.617021 (2720 1460);
PAINT WHITE (2720 1460);
FORCEPROP 1 LAST PART_NUMBER A36096-030
J 0
(2675 1350);
DISPLAY 0.617021 (2675 1350);
PAINT BLUE (2675 1350);
FORCEPROP 1 LAST PACK_TYPE 0402V
J 0
(2900 1475);
DISPLAY 0.617021 (2900 1475);
PAINT SKYBLUE (2900 1475);
FORCEPROP 1 LASTPIN (2900 1450) $PN 2
J 0
(2845 1460);
DISPLAY 0.617021 (2845 1460);
PAINT WHITE (2845 1460);
FORCEPROP 1 LAST LOCATION C9A5
J 0
(2725 1525);
DISPLAY 0.617021 (2725 1525);
PAINT AQUA (2725 1525);
FORCEPROP 1 LAST MATERIAL X7R
J 0
(3050 1475);
DISPLAY 0.617021 (3050 1475);
PAINT SKYBLUE (3050 1475);
FORCEPROP 1 LAST PATH I12
R 1
J 0
(2650 1500);
DISPLAY 0.978723 (2650 1500);
PAINT WHITE (2650 1500);
DISPLAY INVISIBLE (2650 1500);
FORCEPROP 2 LAST CDS_LIB dev_discrete
J 0
(2800 1450);
PAINT ORANGE (2800 1450);
DISPLAY INVISIBLE (2800 1450);
FORCEPROP 2 LAST CDS_LOCATION C9A5
J 0
(2800 1525);
DISPLAY 0.617021 (2800 1525);
PAINT AQUA (2800 1525);
DISPLAY INVISIBLE (2800 1525);
FORCEPROP 2 LAST SEC 1
J 0
(2800 1575);
DISPLAY 1.510638 (2800 1575);
PAINT MONO (2800 1575);
DISPLAY INVISIBLE (2800 1575);
FORCEPROP 2 LAST SEC_TYPE 0402V
R 1
J 0
(2800 1575);
DISPLAY 1.659574 (2800 1575);
PAINT ORANGE (2800 1575);
DISPLAY INVISIBLE (2800 1575);
FORCEPROP 2 LAST CDS_SEC 1
R 1
J 0
(2800 1575);
PAINT ORANGE (2800 1575);
DISPLAY INVISIBLE (2800 1575);
FORCEPROP 2 LAST BOM_COST DEBUG
J 0
(2800 1575);
DISPLAY 1.617021 (2800 1575);
PAINT WHITE (2800 1575);
DISPLAY INVISIBLE (2800 1575);
FORCEPROP 2 LAST ROOM DEBUG
J 0
(2800 1575);
DISPLAY 1.617021 (2800 1575);
PAINT WHITE (2800 1575);
DISPLAY INVISIBLE (2800 1575);
FORCEADD RES..1
(2725 1125);
FORCEPROP 1 LAST VALUE 1.00K
J 2
(2575 1075);
DISPLAY 0.617021 (2575 1075);
PAINT SKYBLUE (2575 1075);
FORCEPROP 1 LAST WATTAGE 1/16W
J 2
(2700 1075);
DISPLAY 0.617021 (2700 1075);
PAINT SKYBLUE (2700 1075);
FORCEPROP 1 LAST LOCATION R1L23
J 0
(2650 1200);
DISPLAY 0.617021 (2650 1200);
PAINT AQUA (2650 1200);
FORCEPROP 1 LAST TOLERANCE 1%
J 0
(2725 1075);
DISPLAY 0.617021 (2725 1075);
PAINT SKYBLUE (2725 1075);
FORCEPROP 1 LASTPIN (2625 1125) $PN 1
J 0
(2637 1137);
DISPLAY 0.617021 (2637 1137);
PAINT WHITE (2637 1137);
FORCEPROP 1 LASTPIN (2825 1125) $PN 2
J 0
(2787 1137);
DISPLAY 0.617021 (2787 1137);
PAINT WHITE (2787 1137);
FORCEPROP 1 LAST PACK_TYPE 0402
J 0
(2850 1075);
DISPLAY 0.617021 (2850 1075);
PAINT SKYBLUE (2850 1075);
FORCEPROP 1 LAST PART_NUMBER G21796-026
J 0
(2850 1150);
DISPLAY 0.617021 (2850 1150);
PAINT BLUE (2850 1150);
FORCEPROP 1 LAST MATERIAL CHIP
J 0
(2975 1075);
DISPLAY 0.617021 (2975 1075);
PAINT SKYBLUE (2975 1075);
FORCEPROP 2 LAST CDS_LIB mstr_discrete
J 0
(2725 1125);
DISPLAY 2.212766 (2725 1125);
PAINT ORANGE (2725 1125);
DISPLAY INVISIBLE (2725 1125);
FORCEPROP 2 LAST CDS_LOCATION R1L23
J 0
(2650 1200);
DISPLAY 0.617021 (2650 1200);
PAINT AQUA (2650 1200);
DISPLAY INVISIBLE (2650 1200);
FORCEPROP 2 LAST ROOM DEBUG
J 0
(2675 1275);
DISPLAY 1.617021 (2675 1275);
PAINT WHITE (2675 1275);
DISPLAY INVISIBLE (2675 1275);
FORCEPROP 2 LAST BOM_COST DEBUG
J 0
(2650 1250);
DISPLAY 1.617021 (2650 1250);
PAINT WHITE (2650 1250);
DISPLAY INVISIBLE (2650 1250);
FORCEPROP 2 LAST SEC_TYPE 0402
J 0
(2650 1250);
DISPLAY 1.659574 (2650 1250);
PAINT ORANGE (2650 1250);
DISPLAY INVISIBLE (2650 1250);
FORCEPROP 1 LAST PATH I13
J 0
(2675 1275);
DISPLAY 0.978723 (2675 1275);
PAINT WHITE (2675 1275);
DISPLAY INVISIBLE (2675 1275);
FORCEPROP 2 LAST SEC 1
J 0
(2675 1325);
DISPLAY 1.510638 (2675 1325);
PAINT MONO (2675 1325);
DISPLAY INVISIBLE (2675 1325);
FORCEADD CAP_A..1
R 1
(2825 925);
FORCEPROP 1 LAST VALUE 0.1UF
J 0
(2475 950);
DISPLAY 0.617021 (2475 950);
PAINT SKYBLUE (2475 950);
FORCEPROP 1 LAST TOLERANCE 10%
J 0
(2675 950);
DISPLAY 0.617021 (2675 950);
PAINT SKYBLUE (2675 950);
FORCEPROP 1 LAST VOLTAGE 16V
J 0
(2600 950);
DISPLAY 0.617021 (2600 950);
PAINT SKYBLUE (2600 950);
FORCEPROP 1 LASTPIN (2725 925) $PN 1
J 0
(2745 935);
DISPLAY 0.617021 (2745 935);
PAINT WHITE (2745 935);
FORCEPROP 1 LAST PART_NUMBER A36096-030
J 0
(2650 825);
DISPLAY 0.617021 (2650 825);
PAINT BLUE (2650 825);
FORCEPROP 1 LAST MATERIAL X7R
J 0
(2925 950);
DISPLAY 0.617021 (2925 950);
PAINT SKYBLUE (2925 950);
FORCEPROP 1 LASTPIN (2925 925) $PN 2
J 0
(2870 935);
DISPLAY 0.617021 (2870 935);
PAINT WHITE (2870 935);
FORCEPROP 1 LAST LOCATION C1L8
J 0
(2775 1000);
DISPLAY 0.617021 (2775 1000);
PAINT AQUA (2775 1000);
FORCEPROP 1 LAST PACK_TYPE 0402V
J 0
(3025 950);
DISPLAY 0.617021 (3025 950);
PAINT SKYBLUE (3025 950);
FORCEPROP 1 LAST PATH I14
R 1
J 0
(2675 975);
DISPLAY 0.978723 (2675 975);
PAINT WHITE (2675 975);
DISPLAY INVISIBLE (2675 975);
FORCEPROP 2 LAST CDS_LIB dev_discrete
J 0
(2825 925);
PAINT ORANGE (2825 925);
DISPLAY INVISIBLE (2825 925);
FORCEPROP 2 LAST CDS_LOCATION C1L8
J 0
(2825 1000);
DISPLAY 0.617021 (2825 1000);
PAINT AQUA (2825 1000);
DISPLAY INVISIBLE (2825 1000);
FORCEPROP 2 LAST CDS_SEC 1
R 1
J 0
(2825 1050);
PAINT ORANGE (2825 1050);
DISPLAY INVISIBLE (2825 1050);
FORCEPROP 2 LAST SEC_TYPE 0402V
R 1
J 0
(2825 1050);
DISPLAY 1.659574 (2825 1050);
PAINT ORANGE (2825 1050);
DISPLAY INVISIBLE (2825 1050);
FORCEPROP 2 LAST ROOM DEBUG
J 0
(2825 1050);
DISPLAY 1.617021 (2825 1050);
PAINT WHITE (2825 1050);
DISPLAY INVISIBLE (2825 1050);
FORCEPROP 2 LAST BOM_COST DEBUG
J 0
(2825 1050);
DISPLAY 1.617021 (2825 1050);
PAINT WHITE (2825 1050);
DISPLAY INVISIBLE (2825 1050);
FORCEPROP 2 LAST SEC 1
J 0
(2825 1050);
DISPLAY 1.510638 (2825 1050);
PAINT MONO (2825 1050);
DISPLAY INVISIBLE (2825 1050);
FORCEADD OFFPAGE..4
(1875 3700);
FORCEPROP 2 LAST $XR0 114 
J 0
(2061 3700);
DISPLAY 0.638298 (2061 3700);
PAINT MONO (2061 3700);
FORCEPROP 1 LAST COMMENT_BODY TRUE
J 0
(1850 3600);
DISPLAY 1.893617 (1850 3600);
PAINT PEACH (1850 3600);
DISPLAY INVISIBLE (1850 3600);
FORCEPROP 2 LAST CDS_LIB mstr_standard
J 0
(1875 3700);
DISPLAY 2.212766 (1875 3700);
PAINT ORANGE (1875 3700);
DISPLAY INVISIBLE (1875 3700);
FORCEPROP 1 LAST OFFPAGE TRUE
J 0
(2200 3575);
PAINT GREEN (2200 3575);
DISPLAY INVISIBLE (2200 3575);
FORCEPROP 2 LAST PATH I15
J 0
(2075 3750);
DISPLAY 1.021277 (2075 3750);
PAINT ORANGE (2075 3750);
DISPLAY INVISIBLE (2075 3750);
FORCEPROP 2 LAST ROOM CPU_XDP_DEBUG
J 0
(2200 3750);
DISPLAY 1.617021 (2200 3750);
PAINT WHITE (2200 3750);
DISPLAY INVISIBLE (2200 3750);
FORCEPROP 2 LAST BOM_COST DEBUG
J 0
(2200 3750);
DISPLAY 1.617021 (2200 3750);
PAINT WHITE (2200 3750);
DISPLAY INVISIBLE (2200 3750);
FORCEADD OFFPAGE..4
(1875 3650);
FORCEPROP 2 LAST $XR0 114 
J 0
(2061 3650);
DISPLAY 0.638298 (2061 3650);
PAINT MONO (2061 3650);
FORCEPROP 1 LAST COMMENT_BODY TRUE
J 0
(1850 3550);
DISPLAY 1.893617 (1850 3550);
PAINT PEACH (1850 3550);
DISPLAY INVISIBLE (1850 3550);
FORCEPROP 2 LAST CDS_LIB mstr_standard
J 0
(1875 3650);
DISPLAY 2.212766 (1875 3650);
PAINT ORANGE (1875 3650);
DISPLAY INVISIBLE (1875 3650);
FORCEPROP 1 LAST OFFPAGE TRUE
J 0
(2200 3525);
PAINT GREEN (2200 3525);
DISPLAY INVISIBLE (2200 3525);
FORCEPROP 2 LAST PATH I16
J 0
(2075 3700);
DISPLAY 1.021277 (2075 3700);
PAINT ORANGE (2075 3700);
DISPLAY INVISIBLE (2075 3700);
FORCEPROP 2 LAST ROOM CPU_XDP_DEBUG
J 0
(2200 3700);
DISPLAY 1.617021 (2200 3700);
PAINT WHITE (2200 3700);
DISPLAY INVISIBLE (2200 3700);
FORCEPROP 2 LAST BOM_COST DEBUG
J 0
(2200 3700);
DISPLAY 1.617021 (2200 3700);
PAINT WHITE (2200 3700);
DISPLAY INVISIBLE (2200 3700);
FORCEADD OFFPAGE..4
(1875 3550);
FORCEPROP 2 LAST $XR0 111 
J 0
(2061 3550);
DISPLAY 0.638298 (2061 3550);
PAINT MONO (2061 3550);
FORCEPROP 2 LAST $XR1 118 
J 0
(2181 3550);
DISPLAY 0.638298 (2181 3550);
PAINT MONO (2181 3550);
FORCEPROP 1 LAST COMMENT_BODY TRUE
J 0
(1850 3450);
DISPLAY 1.893617 (1850 3450);
PAINT PEACH (1850 3450);
DISPLAY INVISIBLE (1850 3450);
FORCEPROP 2 LAST CDS_LIB mstr_standard
J 0
(1875 3550);
DISPLAY 2.212766 (1875 3550);
PAINT ORANGE (1875 3550);
DISPLAY INVISIBLE (1875 3550);
FORCEPROP 1 LAST OFFPAGE TRUE
J 0
(2200 3425);
PAINT GREEN (2200 3425);
DISPLAY INVISIBLE (2200 3425);
FORCEPROP 2 LAST PATH I17
J 0
(2075 3600);
DISPLAY 1.021277 (2075 3600);
PAINT ORANGE (2075 3600);
DISPLAY INVISIBLE (2075 3600);
FORCEPROP 2 LAST ROOM CPU_XDP_DEBUG
J 0
(2175 3600);
DISPLAY 1.617021 (2175 3600);
PAINT WHITE (2175 3600);
DISPLAY INVISIBLE (2175 3600);
FORCEPROP 2 LAST BOM_COST DEBUG
J 0
(2175 3600);
DISPLAY 1.617021 (2175 3600);
PAINT WHITE (2175 3600);
DISPLAY INVISIBLE (2175 3600);
FORCEADD OFFPAGE..4
(1875 3400);
FORCEPROP 2 LAST $XR0 112 
J 0
(2061 3400);
DISPLAY 0.638298 (2061 3400);
PAINT MONO (2061 3400);
FORCEPROP 2 LAST $XR1 118 
J 0
(2181 3400);
DISPLAY 0.638298 (2181 3400);
PAINT MONO (2181 3400);
FORCEPROP 1 LAST COMMENT_BODY TRUE
J 0
(1850 3300);
DISPLAY 1.893617 (1850 3300);
PAINT PEACH (1850 3300);
DISPLAY INVISIBLE (1850 3300);
FORCEPROP 2 LAST CDS_LIB mstr_standard
J 0
(1875 3400);
DISPLAY 2.212766 (1875 3400);
PAINT ORANGE (1875 3400);
DISPLAY INVISIBLE (1875 3400);
FORCEPROP 1 LAST OFFPAGE TRUE
J 0
(2200 3275);
PAINT GREEN (2200 3275);
DISPLAY INVISIBLE (2200 3275);
FORCEPROP 2 LAST PATH I18
J 0
(2200 3450);
DISPLAY 1.021277 (2200 3450);
PAINT ORANGE (2200 3450);
DISPLAY INVISIBLE (2200 3450);
FORCEPROP 2 LAST ROOM CPU_XDP_DEBUG
J 0
(2075 3450);
DISPLAY 1.617021 (2075 3450);
PAINT WHITE (2075 3450);
DISPLAY INVISIBLE (2075 3450);
FORCEPROP 2 LAST BOM_COST DEBUG
J 0
(2075 3450);
DISPLAY 1.617021 (2075 3450);
PAINT WHITE (2075 3450);
DISPLAY INVISIBLE (2075 3450);
FORCEADD OFFPAGE..2
(1875 3300);
FORCEPROP 2 LAST $XR0 118 
J 0
(2064 3300);
DISPLAY 0.638298 (2064 3300);
PAINT MONO (2064 3300);
FORCEPROP 2 LAST $XR1 112 
J 0
(2184 3300);
DISPLAY 0.638298 (2184 3300);
PAINT MONO (2184 3300);
FORCEPROP 1 LAST COMMENT_BODY TRUE
J 0
(1830 3205);
DISPLAY 1.893617 (1830 3205);
PAINT PEACH (1830 3205);
DISPLAY INVISIBLE (1830 3205);
FORCEPROP 2 LAST CDS_LIB mstr_standard
J 0
(1875 3300);
DISPLAY 2.212766 (1875 3300);
PAINT ORANGE (1875 3300);
DISPLAY INVISIBLE (1875 3300);
FORCEPROP 1 LAST OFFPAGE TRUE
J 0
(2200 3175);
PAINT GREEN (2200 3175);
DISPLAY INVISIBLE (2200 3175);
FORCEPROP 2 LAST PATH I19
J 0
(2200 3350);
DISPLAY 1.021277 (2200 3350);
PAINT ORANGE (2200 3350);
DISPLAY INVISIBLE (2200 3350);
FORCEPROP 2 LAST BOM_COST DEBUG
J 0
(2075 3350);
DISPLAY 1.617021 (2075 3350);
PAINT WHITE (2075 3350);
DISPLAY INVISIBLE (2075 3350);
FORCEPROP 2 LAST ROOM CPU_XDP_DEBUG
J 0
(2075 3350);
DISPLAY 1.617021 (2075 3350);
PAINT WHITE (2075 3350);
DISPLAY INVISIBLE (2075 3350);
FORCEADD OFFPAGE..2
(3575 2600);
FORCEPROP 2 LAST $XR0 155 
J 0
(3764 2600);
DISPLAY 0.638298 (3764 2600);
PAINT MONO (3764 2600);
FORCEPROP 2 LAST $XR1 190 
J 0
(3884 2600);
DISPLAY 0.638298 (3884 2600);
PAINT MONO (3884 2600);
FORCEPROP 2 LAST $XR2 247 
J 0
(4004 2600);
DISPLAY 0.638298 (4004 2600);
PAINT MONO (4004 2600);
FORCEPROP 2 LAST $XR3 175 
J 0
(4004 2600);
DISPLAY 0.638298 (4004 2600);
PAINT MONO (4004 2600);
FORCEPROP 1 LAST COMMENT_BODY TRUE
J 0
(3530 2505);
DISPLAY 1.404255 (3530 2505);
PAINT PEACH (3530 2505);
DISPLAY INVISIBLE (3530 2505);
FORCEPROP 2 LAST CDS_LIB mstr_standard
J 0
(3575 2600);
PAINT ORANGE (3575 2600);
DISPLAY INVISIBLE (3575 2600);
FORCEPROP 2 LAST BOM_COST MIO_CHASSIS
J 0
(3300 2650);
DISPLAY 1.617021 (3300 2650);
PAINT WHITE (3300 2650);
DISPLAY INVISIBLE (3300 2650);
FORCEPROP 2 LAST ROOM FPB_CONN
J 0
(3300 2650);
DISPLAY 1.617021 (3300 2650);
PAINT WHITE (3300 2650);
DISPLAY INVISIBLE (3300 2650);
FORCEPROP 2 LAST PATH I2
J 0
(4025 2650);
DISPLAY 1.021277 (4025 2650);
PAINT ORANGE (4025 2650);
DISPLAY INVISIBLE (4025 2650);
FORCEPROP 1 LAST OFFPAGE TRUE
J 0
(3900 2475);
DISPLAY 1.404255 (3900 2475);
PAINT GREEN (3900 2475);
DISPLAY INVISIBLE (3900 2475);
FORCEADD OFFPAGE..2
(1875 3350);
FORCEPROP 2 LAST $XR0 118 
J 0
(2064 3350);
DISPLAY 0.638298 (2064 3350);
PAINT MONO (2064 3350);
FORCEPROP 2 LAST $XR1 112 
J 0
(2184 3350);
DISPLAY 0.638298 (2184 3350);
PAINT MONO (2184 3350);
FORCEPROP 1 LAST COMMENT_BODY TRUE
J 0
(1830 3255);
DISPLAY 1.893617 (1830 3255);
PAINT PEACH (1830 3255);
DISPLAY INVISIBLE (1830 3255);
FORCEPROP 2 LAST CDS_LIB mstr_standard
J 0
(1875 3350);
DISPLAY 2.212766 (1875 3350);
PAINT ORANGE (1875 3350);
DISPLAY INVISIBLE (1875 3350);
FORCEPROP 1 LAST OFFPAGE TRUE
J 0
(2200 3225);
PAINT GREEN (2200 3225);
DISPLAY INVISIBLE (2200 3225);
FORCEPROP 2 LAST PATH I20
J 0
(2075 3400);
DISPLAY 1.021277 (2075 3400);
PAINT ORANGE (2075 3400);
DISPLAY INVISIBLE (2075 3400);
FORCEPROP 2 LAST ROOM CPU_XDP_DEBUG
J 0
(2250 3400);
DISPLAY 1.617021 (2250 3400);
PAINT WHITE (2250 3400);
DISPLAY INVISIBLE (2250 3400);
FORCEPROP 2 LAST BOM_COST DEBUG
J 0
(2250 3400);
DISPLAY 1.617021 (2250 3400);
PAINT WHITE (2250 3400);
DISPLAY INVISIBLE (2250 3400);
FORCEADD OFFPAGE..2
(1875 3250);
FORCEPROP 2 LAST $XR0 118 
J 0
(2064 3250);
DISPLAY 0.638298 (2064 3250);
PAINT MONO (2064 3250);
FORCEPROP 2 LAST $XR1 112 
J 0
(2184 3250);
DISPLAY 0.638298 (2184 3250);
PAINT MONO (2184 3250);
FORCEPROP 1 LAST COMMENT_BODY TRUE
J 0
(1830 3155);
DISPLAY 1.893617 (1830 3155);
PAINT PEACH (1830 3155);
DISPLAY INVISIBLE (1830 3155);
FORCEPROP 2 LAST CDS_LIB mstr_standard
J 0
(1875 3250);
DISPLAY 2.212766 (1875 3250);
PAINT ORANGE (1875 3250);
DISPLAY INVISIBLE (1875 3250);
FORCEPROP 1 LAST OFFPAGE TRUE
J 0
(2200 3125);
PAINT GREEN (2200 3125);
DISPLAY INVISIBLE (2200 3125);
FORCEPROP 2 LAST BOM_COST DEBUG
J 0
(2250 3300);
DISPLAY 1.617021 (2250 3300);
PAINT WHITE (2250 3300);
DISPLAY INVISIBLE (2250 3300);
FORCEPROP 2 LAST ROOM CPU_XDP_DEBUG
J 0
(2250 3300);
DISPLAY 1.617021 (2250 3300);
PAINT WHITE (2250 3300);
DISPLAY INVISIBLE (2250 3300);
FORCEPROP 2 LAST PATH I21
J 0
(2200 3300);
DISPLAY 1.021277 (2200 3300);
PAINT ORANGE (2200 3300);
DISPLAY INVISIBLE (2200 3300);
FORCEADD OFFPAGE..2
(1875 3200);
FORCEPROP 2 LAST $XR0 111 
J 0
(2064 3200);
DISPLAY 0.638298 (2064 3200);
PAINT MONO (2064 3200);
FORCEPROP 2 LAST $XR1 22 
J 0
(2184 3200);
DISPLAY 0.638298 (2184 3200);
PAINT MONO (2184 3200);
FORCEPROP 2 LAST $XR2 56 
J 0
(2274 3200);
DISPLAY 0.638298 (2274 3200);
PAINT MONO (2274 3200);
FORCEPROP 1 LAST COMMENT_BODY TRUE
J 0
(1830 3105);
DISPLAY 1.893617 (1830 3105);
PAINT PEACH (1830 3105);
DISPLAY INVISIBLE (1830 3105);
FORCEPROP 2 LAST CDS_LIB mstr_standard
J 0
(1875 3200);
DISPLAY 2.212766 (1875 3200);
PAINT ORANGE (1875 3200);
DISPLAY INVISIBLE (1875 3200);
FORCEPROP 2 LAST BOM_COST DEBUG
J 0
(2250 3250);
DISPLAY 1.617021 (2250 3250);
PAINT WHITE (2250 3250);
DISPLAY INVISIBLE (2250 3250);
FORCEPROP 2 LAST ROOM CPU_XDP_DEBUG
J 0
(2250 3250);
DISPLAY 1.617021 (2250 3250);
PAINT WHITE (2250 3250);
DISPLAY INVISIBLE (2250 3250);
FORCEPROP 1 LAST OFFPAGE TRUE
J 0
(2200 3075);
PAINT GREEN (2200 3075);
DISPLAY INVISIBLE (2200 3075);
FORCEPROP 2 LAST PATH I22
J 0
(2250 3250);
DISPLAY 1.021277 (2250 3250);
PAINT ORANGE (2250 3250);
DISPLAY INVISIBLE (2250 3250);
FORCEADD OFFPAGE..5
(1975 2150);
FORCEPROP 2 LAST $XR0 111 
J 0
(1720 2150);
DISPLAY 0.638298 (1720 2150);
PAINT MONO (1720 2150);
FORCEPROP 2 LAST $XR1 190 
J 0
(1600 2150);
DISPLAY 0.638298 (1600 2150);
PAINT MONO (1600 2150);
FORCEPROP 2 LAST PATH I23
J 0
(1725 2200);
DISPLAY 1.021277 (1725 2200);
PAINT ORANGE (1725 2200);
DISPLAY INVISIBLE (1725 2200);
FORCEPROP 2 LAST BOM_COST DEBUG
J 0
(1725 2200);
DISPLAY 1.617021 (1725 2200);
PAINT WHITE (1725 2200);
DISPLAY INVISIBLE (1725 2200);
FORCEPROP 2 LAST ROOM CPU_XDP_DEBUG
J 0
(1725 2200);
DISPLAY 1.617021 (1725 2200);
PAINT WHITE (1725 2200);
DISPLAY INVISIBLE (1725 2200);
FORCEPROP 2 LAST CDS_LIB mstr_standard
J 0
(1975 2150);
DISPLAY 2.212766 (1975 2150);
PAINT ORANGE (1975 2150);
DISPLAY INVISIBLE (1975 2150);
FORCEPROP 1 LAST OFFPAGE TRUE
J 0
(2300 2025);
PAINT GREEN (2300 2025);
DISPLAY INVISIBLE (2300 2025);
FORCEPROP 1 LAST COMMENT_BODY TRUE
J 0
(2075 2075);
DISPLAY 1.893617 (2075 2075);
PAINT PEACH (2075 2075);
DISPLAY INVISIBLE (2075 2075);
FORCEADD GND..1
(875 2625);
FORCEPROP 3 LASTPIN (875 2675) SIG_NAME GND\g
J 0
(885 2685);
DISPLAY 0.659574 (885 2685);
PAINT MONO (885 2685);
DISPLAY INVISIBLE (885 2685);
FORCEPROP 2 LAST ROOM CPU_XDP_DEBUG
J 0
(425 2700);
DISPLAY 1.617021 (425 2700);
PAINT WHITE (425 2700);
DISPLAY INVISIBLE (425 2700);
FORCEPROP 2 LAST BOM_COST DEBUG
J 0
(725 2700);
DISPLAY 1.617021 (725 2700);
PAINT WHITE (725 2700);
DISPLAY INVISIBLE (725 2700);
FORCEPROP 1 LAST BODY_TYPE PLUMBING
J 0
(830 2582);
DISPLAY 0.340426 (830 2582);
PAINT GREEN (830 2582);
DISPLAY INVISIBLE (830 2582);
FORCEPROP 1 LAST VOLTAGE 0.0V
J 0
(830 2582);
DISPLAY 0.340426 (830 2582);
PAINT SKYBLUE (830 2582);
DISPLAY INVISIBLE (830 2582);
FORCEPROP 2 LAST CDS_LIB mstr_symbols
J 0
(875 2625);
DISPLAY 2.212766 (875 2625);
PAINT ORANGE (875 2625);
DISPLAY INVISIBLE (875 2625);
FORCEPROP 1 LAST SIZE 1B
J 0
(950 2575);
DISPLAY 1.893617 (950 2575);
PAINT GREEN (950 2575);
DISPLAY INVISIBLE (950 2575);
FORCEPROP 1 LAST PATH I24
J 0
(950 2625);
DISPLAY 0.872340 (950 2625);
PAINT AQUA (950 2625);
DISPLAY INVISIBLE (950 2625);
FORCEPROP 1 LAST HDL_POWER GND
J 0
(875 2775);
PAINT GREEN (875 2775);
DISPLAY INVISIBLE (875 2775);
FORCEADD CAP_A..1
R 2
(750 2925);
FORCEPROP 1 LAST PART_NUMBER D97712-004
J 2
(700 2775);
DISPLAY 0.617021 (700 2775);
PAINT BLUE (700 2775);
FORCEPROP 1 LAST PACK_TYPE 0402V
J 2
(700 2725);
DISPLAY 0.617021 (700 2725);
PAINT SKYBLUE (700 2725);
FORCEPROP 1 LASTPIN (750 2825) $PN 2
J 2
(740 2805);
DISPLAY 0.617021 (740 2805);
PAINT WHITE (740 2805);
FORCEPROP 1 LASTPIN (750 3025) $PN 1
J 2
(740 3005);
DISPLAY 0.617021 (740 3005);
PAINT WHITE (740 3005);
FORCEPROP 1 LAST MATERIAL X6S
J 2
(700 2825);
DISPLAY 0.617021 (700 2825);
PAINT SKYBLUE (700 2825);
FORCEPROP 1 LAST VOLTAGE 6.3V
J 2
(700 2925);
DISPLAY 0.617021 (700 2925);
PAINT SKYBLUE (700 2925);
FORCEPROP 1 LAST TOLERANCE 10%
J 2
(700 2875);
DISPLAY 0.617021 (700 2875);
PAINT SKYBLUE (700 2875);
FORCEPROP 1 LAST VALUE 1.0UF
J 2
(700 2975);
DISPLAY 0.617021 (700 2975);
PAINT SKYBLUE (700 2975);
FORCEPROP 1 LAST LOCATION C9A6
J 2
(700 3025);
DISPLAY 0.617021 (700 3025);
PAINT AQUA (700 3025);
FORCEPROP 2 LAST CDS_LIB dev_discrete
J 0
(750 2925);
PAINT ORANGE (750 2925);
DISPLAY INVISIBLE (750 2925);
FORCEPROP 2 LAST BOM_COST DEBUG
J 0
(700 3000);
DISPLAY 1.617021 (700 3000);
PAINT WHITE (700 3000);
DISPLAY INVISIBLE (700 3000);
FORCEPROP 2 LAST CDS_LOCATION C9A6
J 2
(700 3000);
DISPLAY 0.617021 (700 3000);
PAINT AQUA (700 3000);
DISPLAY INVISIBLE (700 3000);
FORCEPROP 2 LAST ROOM DEBUG
J 2
(700 3025);
DISPLAY 1.617021 (700 3025);
PAINT WHITE (700 3025);
DISPLAY INVISIBLE (700 3025);
FORCEPROP 1 LAST PATH I25
J 2
(700 3075);
DISPLAY 0.978723 (700 3075);
PAINT WHITE (700 3075);
DISPLAY INVISIBLE (700 3075);
FORCEPROP 2 LAST $SEC 1
J 0
(700 3125);
PAINT MONO (700 3125);
DISPLAY INVISIBLE (700 3125);
FORCEPROP 2 LAST CDS_SEC 1
J 0
(700 3125);
PAINT MONO (700 3125);
DISPLAY INVISIBLE (700 3125);
FORCEADD SCONN60_C21100002..1
(350 3950);
FORCEPROP 2 LASTPIN (200 3200) $PN 59
J 2
(190 3210);
DISPLAY 0.617021 (190 3210);
PAINT ORANGE (190 3210);
FORCEPROP 2 LASTPIN (200 3250) $PN 57
J 2
(190 3260);
DISPLAY 0.617021 (190 3260);
PAINT ORANGE (190 3260);
FORCEPROP 2 LASTPIN (200 3300) $PN 55
J 2
(190 3310);
DISPLAY 0.617021 (190 3310);
PAINT ORANGE (190 3310);
FORCEPROP 2 LASTPIN (200 3350) $PN 53
J 2
(190 3360);
DISPLAY 0.617021 (190 3360);
PAINT ORANGE (190 3360);
FORCEPROP 2 LASTPIN (200 3400) $PN 51
J 2
(190 3410);
DISPLAY 0.617021 (190 3410);
PAINT ORANGE (190 3410);
FORCEPROP 2 LASTPIN (200 3450) $PN 49
J 2
(190 3460);
DISPLAY 0.617021 (190 3460);
PAINT ORANGE (190 3460);
FORCEPROP 2 LASTPIN (200 3500) $PN 47
J 2
(190 3510);
DISPLAY 0.617021 (190 3510);
PAINT ORANGE (190 3510);
FORCEPROP 2 LASTPIN (200 3550) $PN 45
J 2
(190 3560);
DISPLAY 0.617021 (190 3560);
PAINT ORANGE (190 3560);
FORCEPROP 2 LASTPIN (200 3600) $PN 43
J 2
(190 3610);
DISPLAY 0.617021 (190 3610);
PAINT ORANGE (190 3610);
FORCEPROP 2 LASTPIN (200 3650) $PN 41
J 2
(190 3660);
DISPLAY 0.617021 (190 3660);
PAINT ORANGE (190 3660);
FORCEPROP 2 LASTPIN (200 3700) $PN 39
J 2
(190 3710);
DISPLAY 0.617021 (190 3710);
PAINT ORANGE (190 3710);
FORCEPROP 2 LASTPIN (200 3750) $PN 37
J 2
(190 3760);
DISPLAY 0.617021 (190 3760);
PAINT ORANGE (190 3760);
FORCEPROP 2 LASTPIN (200 3800) $PN 35
J 2
(190 3810);
DISPLAY 0.617021 (190 3810);
PAINT ORANGE (190 3810);
FORCEPROP 2 LASTPIN (200 3850) $PN 33
J 2
(190 3860);
DISPLAY 0.617021 (190 3860);
PAINT ORANGE (190 3860);
FORCEPROP 2 LASTPIN (200 3900) $PN 31
J 2
(190 3910);
DISPLAY 0.617021 (190 3910);
PAINT ORANGE (190 3910);
FORCEPROP 2 LASTPIN (200 3950) $PN 29
J 2
(190 3960);
DISPLAY 0.617021 (190 3960);
PAINT ORANGE (190 3960);
FORCEPROP 2 LASTPIN (200 4000) $PN 27
J 2
(190 4010);
DISPLAY 0.617021 (190 4010);
PAINT ORANGE (190 4010);
FORCEPROP 2 LASTPIN (200 4050) $PN 25
J 2
(190 4060);
DISPLAY 0.617021 (190 4060);
PAINT ORANGE (190 4060);
FORCEPROP 2 LASTPIN (500 3350) $PN 54
J 0
(510 3360);
DISPLAY 0.617021 (510 3360);
PAINT ORANGE (510 3360);
FORCEPROP 2 LASTPIN (500 3400) $PN 52
J 0
(510 3410);
DISPLAY 0.617021 (510 3410);
PAINT ORANGE (510 3410);
FORCEPROP 2 LASTPIN (500 3200) $PN 60
J 0
(510 3210);
DISPLAY 0.617021 (510 3210);
PAINT ORANGE (510 3210);
FORCEPROP 2 LASTPIN (500 3250) $PN 58
J 0
(510 3260);
DISPLAY 0.617021 (510 3260);
PAINT ORANGE (510 3260);
FORCEPROP 2 LASTPIN (500 3300) $PN 56
J 0
(510 3310);
DISPLAY 0.617021 (510 3310);
PAINT ORANGE (510 3310);
FORCEPROP 2 LASTPIN (500 3450) $PN 50
J 0
(510 3460);
DISPLAY 0.617021 (510 3460);
PAINT ORANGE (510 3460);
FORCEPROP 2 LASTPIN (500 3500) $PN 48
J 0
(510 3510);
DISPLAY 0.617021 (510 3510);
PAINT ORANGE (510 3510);
FORCEPROP 2 LASTPIN (500 3700) $PN 40
J 0
(510 3710);
DISPLAY 0.617021 (510 3710);
PAINT ORANGE (510 3710);
FORCEPROP 2 LASTPIN (500 3750) $PN 38
J 0
(510 3760);
DISPLAY 0.617021 (510 3760);
PAINT ORANGE (510 3760);
FORCEPROP 2 LASTPIN (500 3800) $PN 36
J 0
(510 3810);
DISPLAY 0.617021 (510 3810);
PAINT ORANGE (510 3810);
FORCEPROP 2 LASTPIN (500 3850) $PN 34
J 0
(510 3860);
DISPLAY 0.617021 (510 3860);
PAINT ORANGE (510 3860);
FORCEPROP 2 LASTPIN (500 3900) $PN 32
J 0
(510 3910);
DISPLAY 0.617021 (510 3910);
PAINT ORANGE (510 3910);
FORCEPROP 2 LASTPIN (500 3950) $PN 30
J 0
(510 3960);
DISPLAY 0.617021 (510 3960);
PAINT ORANGE (510 3960);
FORCEPROP 2 LASTPIN (500 4000) $PN 28
J 0
(510 4010);
DISPLAY 0.617021 (510 4010);
PAINT ORANGE (510 4010);
FORCEPROP 2 LASTPIN (500 4050) $PN 26
J 0
(510 4060);
DISPLAY 0.617021 (510 4060);
PAINT ORANGE (510 4060);
FORCEPROP 2 LASTPIN (500 3600) $PN 44
J 0
(510 3610);
DISPLAY 0.617021 (510 3610);
PAINT ORANGE (510 3610);
FORCEPROP 2 LASTPIN (500 3550) $PN 46
J 0
(510 3560);
DISPLAY 0.617021 (510 3560);
PAINT ORANGE (510 3560);
FORCEPROP 2 LASTPIN (500 3650) $PN 42
J 0
(510 3660);
DISPLAY 0.617021 (510 3660);
PAINT ORANGE (510 3660);
FORCEPROP 2 LASTPIN (200 4100) $PN 23
J 2
(190 4110);
DISPLAY 0.617021 (190 4110);
PAINT ORANGE (190 4110);
FORCEPROP 2 LASTPIN (200 4150) $PN 21
J 2
(190 4160);
DISPLAY 0.617021 (190 4160);
PAINT ORANGE (190 4160);
FORCEPROP 2 LASTPIN (200 4200) $PN 19
J 2
(190 4210);
DISPLAY 0.617021 (190 4210);
PAINT ORANGE (190 4210);
FORCEPROP 2 LASTPIN (200 4250) $PN 17
J 2
(190 4260);
DISPLAY 0.617021 (190 4260);
PAINT ORANGE (190 4260);
FORCEPROP 2 LASTPIN (200 4300) $PN 15
J 2
(190 4310);
DISPLAY 0.617021 (190 4310);
PAINT ORANGE (190 4310);
FORCEPROP 2 LASTPIN (200 4350) $PN 13
J 2
(190 4360);
DISPLAY 0.617021 (190 4360);
PAINT ORANGE (190 4360);
FORCEPROP 2 LASTPIN (200 4400) $PN 11
J 2
(190 4410);
DISPLAY 0.617021 (190 4410);
PAINT ORANGE (190 4410);
FORCEPROP 2 LASTPIN (200 4450) $PN 9
J 2
(190 4460);
DISPLAY 0.617021 (190 4460);
PAINT ORANGE (190 4460);
FORCEPROP 2 LASTPIN (200 4500) $PN 7
J 2
(190 4510);
DISPLAY 0.617021 (190 4510);
PAINT ORANGE (190 4510);
FORCEPROP 2 LASTPIN (200 4550) $PN 5
J 2
(190 4560);
DISPLAY 0.617021 (190 4560);
PAINT ORANGE (190 4560);
FORCEPROP 2 LASTPIN (200 4600) $PN 3
J 2
(190 4610);
DISPLAY 0.617021 (190 4610);
PAINT ORANGE (190 4610);
FORCEPROP 2 LASTPIN (200 4650) $PN 1
J 2
(190 4660);
DISPLAY 0.617021 (190 4660);
PAINT ORANGE (190 4660);
FORCEPROP 1 LAST PART_NUMBER C21100-002
J 1
(350 4700);
DISPLAY 0.617021 (350 4700);
PAINT BLUE (350 4700);
FORCEPROP 1 LAST LOCATION J9A3
J 1
(350 4750);
DISPLAY 0.617021 (350 4750);
PAINT AQUA (350 4750);
FORCEPROP 1 LAST PACK_TYPE SMLF
J 1
(350 4850);
DISPLAY 0.617021 (350 4850);
PAINT SKYBLUE (350 4850);
FORCEPROP 1 LAST MATERIAL CONN
J 1
(350 4800);
DISPLAY 0.617021 (350 4800);
PAINT SKYBLUE (350 4800);
FORCEPROP 2 LASTPIN (500 4100) $PN 24
J 0
(510 4110);
DISPLAY 0.617021 (510 4110);
PAINT ORANGE (510 4110);
FORCEPROP 2 LASTPIN (500 4150) $PN 22
J 0
(510 4160);
DISPLAY 0.617021 (510 4160);
PAINT ORANGE (510 4160);
FORCEPROP 2 LASTPIN (500 4200) $PN 20
J 0
(510 4210);
DISPLAY 0.617021 (510 4210);
PAINT ORANGE (510 4210);
FORCEPROP 2 LASTPIN (500 4250) $PN 18
J 0
(510 4260);
DISPLAY 0.617021 (510 4260);
PAINT ORANGE (510 4260);
FORCEPROP 2 LASTPIN (500 4300) $PN 16
J 0
(510 4310);
DISPLAY 0.617021 (510 4310);
PAINT ORANGE (510 4310);
FORCEPROP 2 LASTPIN (500 4350) $PN 14
J 0
(510 4360);
DISPLAY 0.617021 (510 4360);
PAINT ORANGE (510 4360);
FORCEPROP 2 LASTPIN (500 4400) $PN 12
J 0
(510 4410);
DISPLAY 0.617021 (510 4410);
PAINT ORANGE (510 4410);
FORCEPROP 2 LASTPIN (500 4450) $PN 10
J 0
(510 4460);
DISPLAY 0.617021 (510 4460);
PAINT ORANGE (510 4460);
FORCEPROP 2 LASTPIN (500 4500) $PN 8
J 0
(510 4510);
DISPLAY 0.617021 (510 4510);
PAINT ORANGE (510 4510);
FORCEPROP 2 LASTPIN (500 4550) $PN 6
J 0
(510 4560);
DISPLAY 0.617021 (510 4560);
PAINT ORANGE (510 4560);
FORCEPROP 2 LASTPIN (500 4600) $PN 4
J 0
(510 4610);
DISPLAY 0.617021 (510 4610);
PAINT ORANGE (510 4610);
FORCEPROP 2 LASTPIN (500 4650) $PN 2
J 0
(510 4660);
DISPLAY 0.617021 (510 4660);
PAINT ORANGE (510 4660);
FORCEPROP 2 LAST CDS_LIB mstr_sconn
J 0
(350 3950);
PAINT ORANGE (350 3950);
DISPLAY INVISIBLE (350 3950);
FORCEPROP 1 LAST ALLOW_CONNECT TRUE
J 1
(375 4575);
DISPLAY 0.872340 (375 4575);
PAINT GREEN (375 4575);
DISPLAY INVISIBLE (375 4575);
FORCEPROP 2 LAST CDS_LOCATION J9A3
J 1
(350 4750);
DISPLAY 0.617021 (350 4750);
PAINT AQUA (350 4750);
DISPLAY INVISIBLE (350 4750);
FORCEPROP 2 LAST ROOM DEBUG
J 0
(350 4900);
DISPLAY 1.617021 (350 4900);
PAINT WHITE (350 4900);
DISPLAY INVISIBLE (350 4900);
FORCEPROP 2 LAST BOM_COST DEBUG
J 0
(350 4900);
DISPLAY 1.617021 (350 4900);
PAINT WHITE (350 4900);
DISPLAY INVISIBLE (350 4900);
FORCEPROP 1 LAST PATH I26
J 1
(350 5100);
DISPLAY 0.872340 (350 5100);
PAINT WHITE (350 5100);
DISPLAY INVISIBLE (350 5100);
FORCEPROP 2 LAST SEC_TYPE SMLF
J 0
(350 5150);
DISPLAY 1.021277 (350 5150);
PAINT ORANGE (350 5150);
DISPLAY INVISIBLE (350 5150);
FORCEPROP 2 LAST SEC 1
J 0
(350 5150);
DISPLAY 0.680851 (350 5150);
PAINT MONO (350 5150);
DISPLAY INVISIBLE (350 5150);
FORCEADD OFFPAGE..5
(1975 1700);
FORCEPROP 2 LAST $XR0 111 
J 0
(1720 1700);
DISPLAY 0.638298 (1720 1700);
PAINT MONO (1720 1700);
FORCEPROP 2 LAST PATH I27
J 0
(1725 1750);
DISPLAY 1.021277 (1725 1750);
PAINT ORANGE (1725 1750);
DISPLAY INVISIBLE (1725 1750);
FORCEPROP 2 LAST BOM_COST DEBUG
J 0
(1725 1750);
DISPLAY 1.617021 (1725 1750);
PAINT WHITE (1725 1750);
DISPLAY INVISIBLE (1725 1750);
FORCEPROP 2 LAST ROOM CPU_XDP_DEBUG
J 0
(1725 1750);
DISPLAY 1.617021 (1725 1750);
PAINT WHITE (1725 1750);
DISPLAY INVISIBLE (1725 1750);
FORCEPROP 2 LAST CDS_LIB mstr_standard
J 0
(1975 1700);
DISPLAY 2.212766 (1975 1700);
PAINT ORANGE (1975 1700);
DISPLAY INVISIBLE (1975 1700);
FORCEPROP 1 LAST OFFPAGE TRUE
J 0
(2300 1575);
PAINT GREEN (2300 1575);
DISPLAY INVISIBLE (2300 1575);
FORCEPROP 1 LAST COMMENT_BODY TRUE
J 0
(2075 1625);
DISPLAY 1.893617 (2075 1625);
PAINT PEACH (2075 1625);
DISPLAY INVISIBLE (2075 1625);
FORCEADD OFFPAGE..5
(2000 1125);
FORCEPROP 2 LAST $XR0 111 
J 0
(1745 1125);
DISPLAY 0.638298 (1745 1125);
PAINT MONO (1745 1125);
FORCEPROP 2 LAST $XR1 190 
J 0
(1625 1125);
DISPLAY 0.638298 (1625 1125);
PAINT MONO (1625 1125);
FORCEPROP 2 LAST PATH I28
J 0
(1750 1175);
DISPLAY 1.021277 (1750 1175);
PAINT ORANGE (1750 1175);
DISPLAY INVISIBLE (1750 1175);
FORCEPROP 2 LAST BOM_COST DEBUG
J 0
(1750 1175);
DISPLAY 1.617021 (1750 1175);
PAINT WHITE (1750 1175);
DISPLAY INVISIBLE (1750 1175);
FORCEPROP 2 LAST ROOM CPU_XDP_DEBUG
J 0
(1750 1175);
DISPLAY 1.617021 (1750 1175);
PAINT WHITE (1750 1175);
DISPLAY INVISIBLE (1750 1175);
FORCEPROP 2 LAST CDS_LIB mstr_standard
J 0
(2000 1125);
DISPLAY 2.212766 (2000 1125);
PAINT ORANGE (2000 1125);
DISPLAY INVISIBLE (2000 1125);
FORCEPROP 1 LAST OFFPAGE TRUE
J 0
(2325 1000);
PAINT GREEN (2325 1000);
DISPLAY INVISIBLE (2325 1000);
FORCEPROP 1 LAST COMMENT_BODY TRUE
J 0
(2100 1050);
DISPLAY 1.893617 (2100 1050);
PAINT PEACH (2100 1050);
DISPLAY INVISIBLE (2100 1050);
FORCEADD CAP_A..1
(0 2925);
FORCEPROP 1 LAST LOCATION C1L5
J 0
(50 3025);
DISPLAY 0.617021 (50 3025);
PAINT AQUA (50 3025);
FORCEPROP 1 LAST PART_NUMBER D97712-004
J 0
(50 2775);
DISPLAY 0.617021 (50 2775);
PAINT BLUE (50 2775);
FORCEPROP 1 LAST VALUE 1.0UF
J 0
(50 2975);
DISPLAY 0.617021 (50 2975);
PAINT SKYBLUE (50 2975);
FORCEPROP 1 LAST TOLERANCE 10%
J 0
(50 2875);
DISPLAY 0.617021 (50 2875);
PAINT SKYBLUE (50 2875);
FORCEPROP 1 LAST PACK_TYPE 0402V
J 0
(50 2725);
DISPLAY 0.617021 (50 2725);
PAINT SKYBLUE (50 2725);
FORCEPROP 1 LAST VOLTAGE 6.3V
J 0
(50 2925);
DISPLAY 0.617021 (50 2925);
PAINT SKYBLUE (50 2925);
FORCEPROP 1 LAST MATERIAL X6S
J 0
(50 2825);
DISPLAY 0.617021 (50 2825);
PAINT SKYBLUE (50 2825);
FORCEPROP 1 LASTPIN (0 3025) $PN 1
J 0
(10 3005);
DISPLAY 0.617021 (10 3005);
PAINT WHITE (10 3005);
FORCEPROP 1 LASTPIN (0 2825) $PN 2
J 0
(10 2805);
DISPLAY 0.617021 (10 2805);
PAINT WHITE (10 2805);
FORCEPROP 2 LAST CDS_LIB dev_discrete
J 0
(0 2925);
PAINT ORANGE (0 2925);
DISPLAY INVISIBLE (0 2925);
FORCEPROP 2 LAST CDS_LOCATION C1L5
J 0
(50 3000);
DISPLAY 0.617021 (50 3000);
PAINT AQUA (50 3000);
DISPLAY INVISIBLE (50 3000);
FORCEPROP 2 LAST BOM_COST DEBUG
J 0
(50 3000);
DISPLAY 1.617021 (50 3000);
PAINT WHITE (50 3000);
DISPLAY INVISIBLE (50 3000);
FORCEPROP 2 LAST ROOM DEBUG
J 0
(50 3025);
DISPLAY 1.617021 (50 3025);
PAINT WHITE (50 3025);
DISPLAY INVISIBLE (50 3025);
FORCEPROP 2 LAST CDS_SEC 1
J 0
(50 3125);
PAINT MONO (50 3125);
DISPLAY INVISIBLE (50 3125);
FORCEPROP 2 LAST $SEC 1
J 0
(50 3125);
PAINT MONO (50 3125);
DISPLAY INVISIBLE (50 3125);
FORCEPROP 1 LAST PATH I30
J 0
(50 3075);
DISPLAY 0.978723 (50 3075);
PAINT WHITE (50 3075);
DISPLAY INVISIBLE (50 3075);
FORCEADD OFFPAGE..5
(-1175 4600);
FORCEPROP 2 LAST $XR0 118 
J 0
(-1430 4600);
DISPLAY 0.638298 (-1430 4600);
PAINT MONO (-1430 4600);
FORCEPROP 2 LAST $XR1 112 
J 0
(-1550 4600);
DISPLAY 0.638298 (-1550 4600);
PAINT MONO (-1550 4600);
FORCEPROP 1 LAST COMMENT_BODY TRUE
J 0
(-1075 4525);
DISPLAY 1.893617 (-1075 4525);
PAINT PEACH (-1075 4525);
DISPLAY INVISIBLE (-1075 4525);
FORCEPROP 2 LAST CDS_LIB mstr_standard
J 0
(-1175 4600);
DISPLAY 2.212766 (-1175 4600);
PAINT ORANGE (-1175 4600);
DISPLAY INVISIBLE (-1175 4600);
FORCEPROP 2 LAST PATH I31
J 0
(-1425 4650);
DISPLAY 1.021277 (-1425 4650);
PAINT ORANGE (-1425 4650);
DISPLAY INVISIBLE (-1425 4650);
FORCEPROP 2 LAST BOM_COST DEBUG
J 0
(-1375 4650);
DISPLAY 1.617021 (-1375 4650);
PAINT WHITE (-1375 4650);
DISPLAY INVISIBLE (-1375 4650);
FORCEPROP 2 LAST ROOM CPU_XDP_DEBUG
J 0
(-1375 4650);
DISPLAY 1.617021 (-1375 4650);
PAINT WHITE (-1375 4650);
DISPLAY INVISIBLE (-1375 4650);
FORCEPROP 1 LAST OFFPAGE TRUE
J 0
(-850 4475);
PAINT GREEN (-850 4475);
DISPLAY INVISIBLE (-850 4475);
FORCEADD OFFPAGE..1
(-1175 4550);
FORCEPROP 2 LAST $XR0 112 
J 0
(-1457 4550);
DISPLAY 0.638298 (-1457 4550);
PAINT MONO (-1457 4550);
FORCEPROP 2 LAST $XR1 118 
J 0
(-1577 4550);
DISPLAY 0.638298 (-1577 4550);
PAINT MONO (-1577 4550);
FORCEPROP 1 LAST COMMENT_BODY TRUE
J 0
(-1050 4450);
DISPLAY 1.893617 (-1050 4450);
PAINT PEACH (-1050 4450);
DISPLAY INVISIBLE (-1050 4450);
FORCEPROP 2 LAST PATH I32
J 0
(-1450 4600);
DISPLAY 1.021277 (-1450 4600);
PAINT ORANGE (-1450 4600);
DISPLAY INVISIBLE (-1450 4600);
FORCEPROP 2 LAST CDS_LIB mstr_standard
J 0
(-1175 4550);
DISPLAY 2.212766 (-1175 4550);
PAINT ORANGE (-1175 4550);
DISPLAY INVISIBLE (-1175 4550);
FORCEPROP 2 LAST ROOM CPU_XDP_DEBUG
J 0
(-1375 4600);
DISPLAY 1.617021 (-1375 4600);
PAINT WHITE (-1375 4600);
DISPLAY INVISIBLE (-1375 4600);
FORCEPROP 2 LAST BOM_COST DEBUG
J 0
(-1375 4600);
DISPLAY 1.617021 (-1375 4600);
PAINT WHITE (-1375 4600);
DISPLAY INVISIBLE (-1375 4600);
FORCEPROP 1 LAST OFFPAGE TRUE
J 0
(-850 4425);
PAINT GREEN (-850 4425);
DISPLAY INVISIBLE (-850 4425);
FORCEADD RES..1
(-2250 4650);
FORCEPROP 1 LAST VALUE 1.00K
J 2
(-2500 4550);
DISPLAY 0.617021 (-2500 4550);
PAINT SKYBLUE (-2500 4550);
FORCEPROP 1 LAST TOLERANCE 1%
J 0
(-2450 4550);
DISPLAY 0.617021 (-2450 4550);
PAINT SKYBLUE (-2450 4550);
FORCEPROP 1 LAST WATTAGE 1/16W
J 2
(-2225 4550);
DISPLAY 0.617021 (-2225 4550);
PAINT SKYBLUE (-2225 4550);
FORCEPROP 1 LAST PART_NUMBER G21796-026
J 0
(-2550 4600);
DISPLAY 0.617021 (-2550 4600);
PAINT BLUE (-2550 4600);
FORCEPROP 1 LAST PACK_TYPE 0402
J 0
(-2200 4600);
DISPLAY 0.617021 (-2200 4600);
PAINT SKYBLUE (-2200 4600);
FORCEPROP 1 LASTPIN (-2350 4650) $PN 1
J 0
(-2338 4662);
DISPLAY 0.617021 (-2338 4662);
PAINT WHITE (-2338 4662);
FORCEPROP 1 LAST LOCATION R2P2
J 0
(-2300 4700);
DISPLAY 0.617021 (-2300 4700);
PAINT AQUA (-2300 4700);
FORCEPROP 1 LASTPIN (-2150 4650) $PN 2
J 0
(-2188 4662);
DISPLAY 0.617021 (-2188 4662);
PAINT WHITE (-2188 4662);
FORCEPROP 1 LAST MATERIAL CHIP
J 0
(-2150 4550);
DISPLAY 0.617021 (-2150 4550);
PAINT SKYBLUE (-2150 4550);
FORCEPROP 1 LAST PATH I37
J 0
(-2300 4800);
DISPLAY 0.978723 (-2300 4800);
PAINT WHITE (-2300 4800);
DISPLAY INVISIBLE (-2300 4800);
FORCEPROP 2 LAST CDS_LOCATION R2P2
J 0
(-2300 4700);
DISPLAY 0.617021 (-2300 4700);
PAINT AQUA (-2300 4700);
DISPLAY INVISIBLE (-2300 4700);
FORCEPROP 2 LAST BOM_COST DEBUG
J 0
(-2300 4750);
DISPLAY 1.617021 (-2300 4750);
PAINT WHITE (-2300 4750);
DISPLAY INVISIBLE (-2300 4750);
FORCEPROP 2 LAST SEC_TYPE 0402
J 0
(-2300 4750);
DISPLAY 1.659574 (-2300 4750);
PAINT ORANGE (-2300 4750);
DISPLAY INVISIBLE (-2300 4750);
FORCEPROP 2 LAST CDS_LIB mstr_discrete
J 0
(-2250 4650);
DISPLAY 2.212766 (-2250 4650);
PAINT ORANGE (-2250 4650);
DISPLAY INVISIBLE (-2250 4650);
FORCEPROP 2 LAST SEC 1
J 0
(-2300 4850);
DISPLAY 1.510638 (-2300 4850);
PAINT MONO (-2300 4850);
DISPLAY INVISIBLE (-2300 4850);
FORCEPROP 2 LAST ROOM DEBUG
J 0
(-2300 4800);
DISPLAY 1.617021 (-2300 4800);
PAINT WHITE (-2300 4800);
DISPLAY INVISIBLE (-2300 4800);
FORCEADD OFFPAGE..5
(-2950 4650);
FORCEPROP 2 LAST $XR0 121 
J 0
(-3235 4650);
DISPLAY 0.638298 (-3235 4650);
PAINT MONO (-3235 4650);
FORCEPROP 2 LAST $XR1 125 
J 0
(-3355 4650);
DISPLAY 0.638298 (-3355 4650);
PAINT MONO (-3355 4650);
FORCEPROP 2 LAST $XR2 154 
J 0
(-3475 4650);
DISPLAY 0.638298 (-3475 4650);
PAINT MONO (-3475 4650);
FORCEPROP 2 LAST BOM_COST DEBUG
J 0
(-3150 4700);
DISPLAY 1.617021 (-3150 4700);
PAINT WHITE (-3150 4700);
DISPLAY INVISIBLE (-3150 4700);
FORCEPROP 2 LAST ROOM CPU_XDP_DEBUG
J 0
(-3150 4700);
DISPLAY 1.617021 (-3150 4700);
PAINT WHITE (-3150 4700);
DISPLAY INVISIBLE (-3150 4700);
FORCEPROP 2 LAST PATH I38
J 0
(-3200 4700);
DISPLAY 1.021277 (-3200 4700);
PAINT ORANGE (-3200 4700);
DISPLAY INVISIBLE (-3200 4700);
FORCEPROP 1 LAST COMMENT_BODY TRUE
J 0
(-2850 4575);
DISPLAY 1.893617 (-2850 4575);
PAINT PEACH (-2850 4575);
DISPLAY INVISIBLE (-2850 4575);
FORCEPROP 1 LAST OFFPAGE TRUE
J 0
(-2625 4525);
PAINT GREEN (-2625 4525);
DISPLAY INVISIBLE (-2625 4525);
FORCEPROP 2 LAST CDS_LIB mstr_standard
J 0
(-2950 4650);
DISPLAY 2.212766 (-2950 4650);
PAINT ORANGE (-2950 4650);
DISPLAY INVISIBLE (-2950 4650);
FORCEADD GND..1
(-100 2625);
FORCEPROP 3 LASTPIN (-100 2675) SIG_NAME GND\g
J 0
(-90 2685);
DISPLAY 0.659574 (-90 2685);
PAINT MONO (-90 2685);
DISPLAY INVISIBLE (-90 2685);
FORCEPROP 2 LAST ROOM CPU_XDP_DEBUG
J 0
(-550 2700);
DISPLAY 1.617021 (-550 2700);
PAINT WHITE (-550 2700);
DISPLAY INVISIBLE (-550 2700);
FORCEPROP 1 LAST BODY_TYPE PLUMBING
J 0
(-145 2582);
DISPLAY 0.340426 (-145 2582);
PAINT GREEN (-145 2582);
DISPLAY INVISIBLE (-145 2582);
FORCEPROP 2 LAST BOM_COST DEBUG
J 0
(-250 2700);
DISPLAY 1.617021 (-250 2700);
PAINT WHITE (-250 2700);
DISPLAY INVISIBLE (-250 2700);
FORCEPROP 1 LAST VOLTAGE 0.0V
J 0
(-145 2582);
DISPLAY 0.340426 (-145 2582);
PAINT SKYBLUE (-145 2582);
DISPLAY INVISIBLE (-145 2582);
FORCEPROP 1 LAST SIZE 1B
J 0
(-25 2575);
DISPLAY 1.893617 (-25 2575);
PAINT GREEN (-25 2575);
DISPLAY INVISIBLE (-25 2575);
FORCEPROP 1 LAST PATH I39
J 0
(-25 2625);
DISPLAY 0.872340 (-25 2625);
PAINT AQUA (-25 2625);
DISPLAY INVISIBLE (-25 2625);
FORCEPROP 2 LAST CDS_LIB mstr_symbols
J 0
(-100 2625);
DISPLAY 2.212766 (-100 2625);
PAINT ORANGE (-100 2625);
DISPLAY INVISIBLE (-100 2625);
FORCEPROP 1 LAST HDL_POWER GND
J 0
(-100 2775);
PAINT GREEN (-100 2775);
DISPLAY INVISIBLE (-100 2775);
FORCEADD OFFPAGE..2
(2850 3500);
FORCEPROP 2 LAST $XR0 111 
J 0
(3039 3500);
DISPLAY 0.638298 (3039 3500);
PAINT MONO (3039 3500);
FORCEPROP 1 LAST COMMENT_BODY TRUE
J 0
(2805 3405);
DISPLAY 1.893617 (2805 3405);
PAINT PEACH (2805 3405);
DISPLAY INVISIBLE (2805 3405);
FORCEPROP 2 LAST CDS_LIB mstr_standard
J 0
(2850 3500);
PAINT ORANGE (2850 3500);
DISPLAY INVISIBLE (2850 3500);
FORCEPROP 1 LAST OFFPAGE TRUE
J 0
(3175 3375);
PAINT GREEN (3175 3375);
DISPLAY INVISIBLE (3175 3375);
FORCEPROP 2 LAST PATH I4
J 0
(3300 3550);
DISPLAY 1.021277 (3300 3550);
PAINT ORANGE (3300 3550);
DISPLAY INVISIBLE (3300 3550);
FORCEPROP 2 LAST BOM_COST DEBUG
J 0
(3225 3550);
DISPLAY 1.617021 (3225 3550);
PAINT WHITE (3225 3550);
DISPLAY INVISIBLE (3225 3550);
FORCEPROP 2 LAST ROOM CPU_XDP_DEBUG
J 0
(3225 3550);
DISPLAY 1.617021 (3225 3550);
PAINT WHITE (3225 3550);
DISPLAY INVISIBLE (3225 3550);
FORCEADD OFFPAGE..5
(-1175 3650);
FORCEPROP 2 LAST $XR0 111 
J 0
(-1430 3650);
DISPLAY 0.638298 (-1430 3650);
PAINT MONO (-1430 3650);
FORCEPROP 2 LAST $XR1 190 
J 0
(-1550 3650);
DISPLAY 0.638298 (-1550 3650);
PAINT MONO (-1550 3650);
FORCEPROP 1 LAST COMMENT_BODY TRUE
J 0
(-1075 3575);
DISPLAY 1.893617 (-1075 3575);
PAINT PEACH (-1075 3575);
DISPLAY INVISIBLE (-1075 3575);
FORCEPROP 2 LAST BOM_COST DEBUG
J 0
(-1425 3700);
DISPLAY 1.617021 (-1425 3700);
PAINT WHITE (-1425 3700);
DISPLAY INVISIBLE (-1425 3700);
FORCEPROP 2 LAST PATH I46
J 0
(-1425 3700);
DISPLAY 1.021277 (-1425 3700);
PAINT ORANGE (-1425 3700);
DISPLAY INVISIBLE (-1425 3700);
FORCEPROP 2 LAST ROOM CPU_XDP_DEBUG
J 0
(-1425 3700);
DISPLAY 1.617021 (-1425 3700);
PAINT WHITE (-1425 3700);
DISPLAY INVISIBLE (-1425 3700);
FORCEPROP 2 LAST CDS_LIB mstr_standard
J 0
(-1175 3650);
DISPLAY 2.212766 (-1175 3650);
PAINT ORANGE (-1175 3650);
DISPLAY INVISIBLE (-1175 3650);
FORCEPROP 1 LAST OFFPAGE TRUE
J 0
(-850 3525);
PAINT GREEN (-850 3525);
DISPLAY INVISIBLE (-850 3525);
FORCEADD OFFPAGE..5
(-1175 3550);
FORCEPROP 2 LAST $XR0 111 
J 0
(-1430 3550);
DISPLAY 0.638298 (-1430 3550);
PAINT MONO (-1430 3550);
FORCEPROP 2 LAST $XR1 118 
J 0
(-1550 3550);
DISPLAY 0.638298 (-1550 3550);
PAINT MONO (-1550 3550);
FORCEPROP 2 LAST $XR2 22 
J 0
(-1640 3550);
DISPLAY 0.638298 (-1640 3550);
PAINT MONO (-1640 3550);
FORCEPROP 2 LAST $XR3 56 
J 0
(-1730 3550);
DISPLAY 0.638298 (-1730 3550);
PAINT MONO (-1730 3550);
FORCEPROP 1 LAST COMMENT_BODY TRUE
J 0
(-1075 3475);
DISPLAY 1.893617 (-1075 3475);
PAINT PEACH (-1075 3475);
DISPLAY INVISIBLE (-1075 3475);
FORCEPROP 2 LAST CDS_LIB mstr_standard
J 0
(-1175 3550);
DISPLAY 2.212766 (-1175 3550);
PAINT ORANGE (-1175 3550);
DISPLAY INVISIBLE (-1175 3550);
FORCEPROP 2 LAST ROOM CPU_XDP_DEBUG
J 0
(-1375 3600);
DISPLAY 1.617021 (-1375 3600);
PAINT WHITE (-1375 3600);
DISPLAY INVISIBLE (-1375 3600);
FORCEPROP 2 LAST BOM_COST DEBUG
J 0
(-1375 3600);
DISPLAY 1.617021 (-1375 3600);
PAINT WHITE (-1375 3600);
DISPLAY INVISIBLE (-1375 3600);
FORCEPROP 2 LAST PATH I47
J 0
(-1425 3600);
DISPLAY 1.021277 (-1425 3600);
PAINT ORANGE (-1425 3600);
DISPLAY INVISIBLE (-1425 3600);
FORCEPROP 1 LAST OFFPAGE TRUE
J 0
(-850 3425);
PAINT GREEN (-850 3425);
DISPLAY INVISIBLE (-850 3425);
FORCEADD OFFPAGE..5
(-1175 3500);
FORCEPROP 2 LAST $XR0 111 
J 0
(-1430 3500);
DISPLAY 0.638298 (-1430 3500);
PAINT MONO (-1430 3500);
FORCEPROP 2 LAST $XR1 190 
J 0
(-1550 3500);
DISPLAY 0.638298 (-1550 3500);
PAINT MONO (-1550 3500);
FORCEPROP 1 LAST COMMENT_BODY TRUE
J 0
(-1075 3425);
DISPLAY 1.893617 (-1075 3425);
PAINT PEACH (-1075 3425);
DISPLAY INVISIBLE (-1075 3425);
FORCEPROP 2 LAST PATH I48
J 0
(-1425 3550);
DISPLAY 1.021277 (-1425 3550);
PAINT ORANGE (-1425 3550);
DISPLAY INVISIBLE (-1425 3550);
FORCEPROP 2 LAST BOM_COST DEBUG
J 0
(-1425 3550);
DISPLAY 1.617021 (-1425 3550);
PAINT WHITE (-1425 3550);
DISPLAY INVISIBLE (-1425 3550);
FORCEPROP 2 LAST ROOM CPU_XDP_DEBUG
J 0
(-1425 3550);
DISPLAY 1.617021 (-1425 3550);
PAINT WHITE (-1425 3550);
DISPLAY INVISIBLE (-1425 3550);
FORCEPROP 2 LAST CDS_LIB mstr_standard
J 0
(-1175 3500);
DISPLAY 2.212766 (-1175 3500);
PAINT ORANGE (-1175 3500);
DISPLAY INVISIBLE (-1175 3500);
FORCEPROP 1 LAST OFFPAGE TRUE
J 0
(-850 3375);
PAINT GREEN (-850 3375);
DISPLAY INVISIBLE (-850 3375);
FORCEADD OFFPAGE..3
R 2
(-1175 3400);
FORCEPROP 2 LAST $XR0 101 
J 0
(-1455 3400);
DISPLAY 0.638298 (-1455 3400);
PAINT MONO (-1455 3400);
FORCEPROP 2 LAST $XR1 102 
J 0
(-1575 3400);
DISPLAY 0.638298 (-1575 3400);
PAINT MONO (-1575 3400);
FORCEPROP 2 LAST $XR2 138 
J 0
(-1695 3400);
DISPLAY 0.638298 (-1695 3400);
PAINT MONO (-1695 3400);
FORCEPROP 2 LAST $XR3 156 
J 0
(-1815 3400);
DISPLAY 0.638298 (-1815 3400);
PAINT MONO (-1815 3400);
FORCEPROP 2 LAST $XR4 159 
J 0
(-1935 3400);
DISPLAY 0.638298 (-1935 3400);
PAINT MONO (-1935 3400);
FORCEPROP 2 LAST $XR5 247 
J 0
(-1935 3400);
DISPLAY 0.638298 (-1935 3400);
PAINT MONO (-1935 3400);
FORCEPROP 2 LAST BOM_COST MEM_VRD_B*
J 2
(-1650 3475);
DISPLAY 1.617021 (-1650 3475);
PAINT WHITE (-1650 3475);
DISPLAY INVISIBLE (-1650 3475);
FORCEPROP 1 LAST OFFPAGE TRUE
J 2
(-1500 3275);
PAINT GREEN (-1500 3275);
DISPLAY INVISIBLE (-1500 3275);
FORCEPROP 2 LAST PATH I49
J 0
(-1450 3450);
DISPLAY 1.021277 (-1450 3450);
PAINT ORANGE (-1450 3450);
DISPLAY INVISIBLE (-1450 3450);
FORCEPROP 1 LAST COMMENT_BODY TRUE
J 2
(-1125 3300);
DISPLAY 1.042553 (-1125 3300);
PAINT PEACH (-1125 3300);
DISPLAY INVISIBLE (-1125 3300);
FORCEPROP 2 LAST CDS_LIB mstr_standard
J 2
(-1175 3400);
DISPLAY 1.617021 (-1175 3400);
PAINT ORANGE (-1175 3400);
DISPLAY INVISIBLE (-1175 3400);
FORCEPROP 2 LAST ROOM VDDQ_AB_VR
J 2
(-775 3475);
DISPLAY 1.212766 (-775 3475);
PAINT WHITE (-775 3475);
DISPLAY INVISIBLE (-775 3475);
FORCEADD OFFPAGE..5
(-1175 3300);
FORCEPROP 2 LAST $XR0 112 
J 0
(-1430 3300);
DISPLAY 0.638298 (-1430 3300);
PAINT MONO (-1430 3300);
FORCEPROP 2 LAST $XR1 118 
J 0
(-1550 3300);
DISPLAY 0.638298 (-1550 3300);
PAINT MONO (-1550 3300);
FORCEPROP 2 LAST PATH I50
J 0
(-1425 3350);
DISPLAY 1.021277 (-1425 3350);
PAINT ORANGE (-1425 3350);
DISPLAY INVISIBLE (-1425 3350);
FORCEPROP 2 LAST BOM_COST DEBUG
J 0
(-1375 3350);
DISPLAY 1.617021 (-1375 3350);
PAINT WHITE (-1375 3350);
DISPLAY INVISIBLE (-1375 3350);
FORCEPROP 2 LAST ROOM CPU_XDP_DEBUG
J 0
(-1375 3350);
DISPLAY 1.617021 (-1375 3350);
PAINT WHITE (-1375 3350);
DISPLAY INVISIBLE (-1375 3350);
FORCEPROP 1 LAST COMMENT_BODY TRUE
J 0
(-1075 3225);
DISPLAY 1.893617 (-1075 3225);
PAINT PEACH (-1075 3225);
DISPLAY INVISIBLE (-1075 3225);
FORCEPROP 2 LAST CDS_LIB mstr_standard
J 0
(-1175 3300);
DISPLAY 1.617021 (-1175 3300);
PAINT ORANGE (-1175 3300);
DISPLAY INVISIBLE (-1175 3300);
FORCEPROP 1 LAST OFFPAGE TRUE
J 0
(-850 3175);
PAINT GREEN (-850 3175);
DISPLAY INVISIBLE (-850 3175);
FORCEADD OFFPAGE..1
(-1175 3350);
FORCEPROP 2 LAST $XR0 138 
J 0
(-1457 3350);
DISPLAY 0.638298 (-1457 3350);
PAINT MONO (-1457 3350);
FORCEPROP 2 LAST $XR1 159 
J 0
(-1577 3350);
DISPLAY 0.638298 (-1577 3350);
PAINT MONO (-1577 3350);
FORCEPROP 2 LAST $XR2 101 
J 0
(-1697 3350);
DISPLAY 0.638298 (-1697 3350);
PAINT MONO (-1697 3350);
FORCEPROP 2 LAST $XR3 102 
J 0
(-1817 3350);
DISPLAY 0.638298 (-1817 3350);
PAINT MONO (-1817 3350);
FORCEPROP 2 LAST $XR4 156 
J 0
(-1937 3350);
DISPLAY 0.638298 (-1937 3350);
PAINT MONO (-1937 3350);
FORCEPROP 2 LAST $XR5 247 
J 0
(-1937 3350);
DISPLAY 0.638298 (-1937 3350);
PAINT MONO (-1937 3350);
FORCEPROP 2 LAST PATH I51
J 0
(-1450 3400);
DISPLAY 1.021277 (-1450 3400);
PAINT ORANGE (-1450 3400);
DISPLAY INVISIBLE (-1450 3400);
FORCEPROP 2 LAST BOM_COST DEBUG
J 0
(-1425 3400);
DISPLAY 1.617021 (-1425 3400);
PAINT WHITE (-1425 3400);
DISPLAY INVISIBLE (-1425 3400);
FORCEPROP 2 LAST ROOM CPU_XDP_DEBUG
J 0
(-1425 3400);
DISPLAY 1.617021 (-1425 3400);
PAINT WHITE (-1425 3400);
DISPLAY INVISIBLE (-1425 3400);
FORCEPROP 1 LAST COMMENT_BODY TRUE
J 0
(-1050 3250);
DISPLAY 1.893617 (-1050 3250);
PAINT PEACH (-1050 3250);
DISPLAY INVISIBLE (-1050 3250);
FORCEPROP 2 LAST CDS_LIB mstr_standard
J 0
(-1175 3350);
DISPLAY 2.212766 (-1175 3350);
PAINT ORANGE (-1175 3350);
DISPLAY INVISIBLE (-1175 3350);
FORCEPROP 1 LAST OFFPAGE TRUE
J 0
(-850 3225);
PAINT GREEN (-850 3225);
DISPLAY INVISIBLE (-850 3225);
FORCEADD OFFPAGE..5
(-1175 3250);
FORCEPROP 2 LAST $XR0 21 
J 0
(-1429 3250);
DISPLAY 0.638298 (-1429 3250);
PAINT MONO (-1429 3250);
FORCEPROP 2 LAST $XR1 55 
J 0
(-1519 3250);
DISPLAY 0.638298 (-1519 3250);
PAINT MONO (-1519 3250);
FORCEPROP 2 LAST $XR2 112 
J 0
(-1639 3250);
DISPLAY 0.638298 (-1639 3250);
PAINT MONO (-1639 3250);
FORCEPROP 2 LAST PATH I52
J 0
(-1425 3300);
DISPLAY 1.021277 (-1425 3300);
PAINT ORANGE (-1425 3300);
DISPLAY INVISIBLE (-1425 3300);
FORCEPROP 2 LAST BOM_COST DEBUG
J 0
(-1375 3300);
DISPLAY 1.617021 (-1375 3300);
PAINT WHITE (-1375 3300);
DISPLAY INVISIBLE (-1375 3300);
FORCEPROP 2 LAST ROOM CPU_XDP_DEBUG
J 0
(-1375 3300);
DISPLAY 1.617021 (-1375 3300);
PAINT WHITE (-1375 3300);
DISPLAY INVISIBLE (-1375 3300);
FORCEPROP 1 LAST COMMENT_BODY TRUE
J 0
(-1075 3175);
DISPLAY 1.893617 (-1075 3175);
PAINT PEACH (-1075 3175);
DISPLAY INVISIBLE (-1075 3175);
FORCEPROP 2 LAST CDS_LIB mstr_standard
J 0
(-1175 3250);
DISPLAY 2.212766 (-1175 3250);
PAINT ORANGE (-1175 3250);
DISPLAY INVISIBLE (-1175 3250);
FORCEPROP 1 LAST OFFPAGE TRUE
J 0
(-850 3125);
PAINT GREEN (-850 3125);
DISPLAY INVISIBLE (-850 3125);
FORCEADD PVCCIO_CPU0..1
(-925 1600);
FORCEPROP 3 LASTPIN (-925 1550) SIG_NAME PVCCIO_CPU0\g
J 0
(-915 1560);
DISPLAY 0.659574 (-915 1560);
PAINT MONO (-915 1560);
DISPLAY INVISIBLE (-915 1560);
FORCEPROP 1 LAST VOLTAGE 1.1V
J 0
(-970 1557);
DISPLAY 0.340426 (-970 1557);
PAINT SKYBLUE (-970 1557);
DISPLAY INVISIBLE (-970 1557);
FORCEPROP 1 LAST HDL_POWER PVCCIO_CPU0
J 1
(-925 1650);
DISPLAY 0.872340 (-925 1650);
PAINT GREEN (-925 1650);
DISPLAY INVISIBLE (-925 1650);
FORCEPROP 2 LAST CDS_LIB mstr_symbols
J 0
(-925 1600);
PAINT ORANGE (-925 1600);
DISPLAY INVISIBLE (-925 1600);
FORCEPROP 1 LAST BODY_TYPE PLUMBING
J 0
(-970 1557);
DISPLAY 0.340426 (-970 1557);
PAINT GREEN (-970 1557);
DISPLAY INVISIBLE (-970 1557);
FORCEPROP 1 LAST PATH I54
J 0
(-875 1625);
DISPLAY 0.872340 (-875 1625);
PAINT AQUA (-875 1625);
DISPLAY INVISIBLE (-875 1625);
FORCEADD RES..1
(-1475 1425);
FORCEPROP 1 LAST VALUE 475.0
J 2
(-1500 1375);
DISPLAY 0.617021 (-1500 1375);
PAINT SKYBLUE (-1500 1375);
FORCEPROP 1 LAST WATTAGE 1/16W
J 2
(-1500 1325);
DISPLAY 0.617021 (-1500 1325);
PAINT SKYBLUE (-1500 1325);
FORCEPROP 1 LASTPIN (-1575 1425) $PN 1
J 0
(-1563 1437);
DISPLAY 0.617021 (-1563 1437);
PAINT WHITE (-1563 1437);
FORCEPROP 1 LAST TOLERANCE 1%
J 0
(-1475 1375);
DISPLAY 0.617021 (-1475 1375);
PAINT SKYBLUE (-1475 1375);
FORCEPROP 1 LAST LOCATION R9A4
J 0
(-1525 1475);
DISPLAY 0.617021 (-1525 1475);
PAINT AQUA (-1525 1475);
FORCEPROP 1 LASTPIN (-1375 1425) $PN 2
J 0
(-1413 1437);
DISPLAY 0.617021 (-1413 1437);
PAINT WHITE (-1413 1437);
FORCEPROP 1 LAST MATERIAL CHIP
J 0
(-1475 1325);
DISPLAY 0.617021 (-1475 1325);
PAINT SKYBLUE (-1475 1325);
FORCEPROP 1 LAST PART_NUMBER G21796-077
J 0
(-1325 1450);
DISPLAY 0.617021 (-1325 1450);
PAINT BLUE (-1325 1450);
FORCEPROP 1 LAST PACK_TYPE 0402
J 0
(-1325 1375);
DISPLAY 0.617021 (-1325 1375);
PAINT SKYBLUE (-1325 1375);
FORCEPROP 2 LAST CDS_LOCATION R9A4
J 0
(-1525 1475);
DISPLAY 0.617021 (-1525 1475);
PAINT AQUA (-1525 1475);
DISPLAY INVISIBLE (-1525 1475);
FORCEPROP 2 LAST CDS_LIB mstr_discrete
J 0
(-1475 1425);
DISPLAY 2.212766 (-1475 1425);
PAINT ORANGE (-1475 1425);
DISPLAY INVISIBLE (-1475 1425);
FORCEPROP 2 LAST BOM_COST DEBUG
J 0
(-1525 1525);
DISPLAY 1.617021 (-1525 1525);
PAINT WHITE (-1525 1525);
DISPLAY INVISIBLE (-1525 1525);
FORCEPROP 2 LAST SEC_TYPE 0402
J 0
(-1525 1525);
DISPLAY 1.659574 (-1525 1525);
PAINT ORANGE (-1525 1525);
DISPLAY INVISIBLE (-1525 1525);
FORCEPROP 2 LAST ROOM DEBUG
J 0
(-1525 1575);
DISPLAY 1.617021 (-1525 1575);
PAINT WHITE (-1525 1575);
DISPLAY INVISIBLE (-1525 1575);
FORCEPROP 2 LAST SEC 1
J 0
(-1525 1625);
DISPLAY 1.510638 (-1525 1625);
PAINT MONO (-1525 1625);
DISPLAY INVISIBLE (-1525 1625);
FORCEPROP 1 LAST PATH I55
J 0
(-1525 1575);
DISPLAY 0.978723 (-1525 1575);
PAINT WHITE (-1525 1575);
DISPLAY INVISIBLE (-1525 1575);
FORCEADD RES..1
(-1475 1100);
FORCEPROP 1 LAST MATERIAL CHIP
J 0
(-1475 1000);
DISPLAY 0.617021 (-1475 1000);
PAINT SKYBLUE (-1475 1000);
FORCEPROP 1 LAST WATTAGE 1/16W
J 2
(-1500 1000);
DISPLAY 0.617021 (-1500 1000);
PAINT SKYBLUE (-1500 1000);
FORCEPROP 1 LAST VALUE 150.0
J 2
(-1500 1050);
DISPLAY 0.617021 (-1500 1050);
PAINT SKYBLUE (-1500 1050);
FORCEPROP 1 LASTPIN (-1575 1100) $PN 1
J 0
(-1563 1112);
DISPLAY 0.617021 (-1563 1112);
PAINT WHITE (-1563 1112);
FORCEPROP 1 LAST TOLERANCE 1%
J 0
(-1475 1050);
DISPLAY 0.617021 (-1475 1050);
PAINT SKYBLUE (-1475 1050);
FORCEPROP 1 LASTPIN (-1375 1100) $PN 2
J 0
(-1413 1112);
DISPLAY 0.617021 (-1413 1112);
PAINT WHITE (-1413 1112);
FORCEPROP 1 LAST LOCATION R1L17
J 0
(-1525 1150);
DISPLAY 0.617021 (-1525 1150);
PAINT AQUA (-1525 1150);
FORCEPROP 1 LAST PART_NUMBER G21796-009
J 0
(-1325 1125);
DISPLAY 0.617021 (-1325 1125);
PAINT BLUE (-1325 1125);
FORCEPROP 1 LAST PACK_TYPE 0402
J 0
(-1325 1050);
DISPLAY 0.617021 (-1325 1050);
PAINT SKYBLUE (-1325 1050);
FORCEPROP 2 LAST CDS_LOCATION R1L17
J 0
(-1525 1150);
DISPLAY 0.617021 (-1525 1150);
PAINT AQUA (-1525 1150);
DISPLAY INVISIBLE (-1525 1150);
FORCEPROP 2 LAST SEC_TYPE 0402
J 0
(-1525 1200);
DISPLAY 1.659574 (-1525 1200);
PAINT ORANGE (-1525 1200);
DISPLAY INVISIBLE (-1525 1200);
FORCEPROP 2 LAST BOM_COST DEBUG
J 0
(-1525 1200);
DISPLAY 1.617021 (-1525 1200);
PAINT WHITE (-1525 1200);
DISPLAY INVISIBLE (-1525 1200);
FORCEPROP 2 LAST CDS_LIB mstr_discrete
J 0
(-1475 1100);
DISPLAY 2.212766 (-1475 1100);
PAINT ORANGE (-1475 1100);
DISPLAY INVISIBLE (-1475 1100);
FORCEPROP 2 LAST ROOM DEBUG
J 0
(-1525 1250);
DISPLAY 1.617021 (-1525 1250);
PAINT WHITE (-1525 1250);
DISPLAY INVISIBLE (-1525 1250);
FORCEPROP 1 LAST PATH I56
J 0
(-1525 1250);
DISPLAY 0.978723 (-1525 1250);
PAINT WHITE (-1525 1250);
DISPLAY INVISIBLE (-1525 1250);
FORCEPROP 2 LAST SEC 1
J 0
(-1525 1300);
DISPLAY 1.510638 (-1525 1300);
PAINT MONO (-1525 1300);
DISPLAY INVISIBLE (-1525 1300);
FORCEADD RES..1
(-1375 500);
FORCEPROP 1 LAST VALUE 1.00K
J 2
(-1400 450);
DISPLAY 0.617021 (-1400 450);
PAINT SKYBLUE (-1400 450);
FORCEPROP 1 LAST WATTAGE 1/16W
J 2
(-1400 400);
DISPLAY 0.617021 (-1400 400);
PAINT SKYBLUE (-1400 400);
FORCEPROP 1 LAST TOLERANCE 1%
J 0
(-1350 450);
DISPLAY 0.617021 (-1350 450);
PAINT SKYBLUE (-1350 450);
FORCEPROP 1 LAST PACK_TYPE 0402
J 0
(-1225 450);
DISPLAY 0.617021 (-1225 450);
PAINT SKYBLUE (-1225 450);
FORCEPROP 1 LAST MATERIAL CHIP
J 0
(-1375 400);
DISPLAY 0.617021 (-1375 400);
PAINT SKYBLUE (-1375 400);
FORCEPROP 1 LASTPIN (-1275 500) $PN 2
J 0
(-1313 512);
DISPLAY 0.617021 (-1313 512);
PAINT WHITE (-1313 512);
FORCEPROP 1 LASTPIN (-1475 500) $PN 1
J 0
(-1463 512);
DISPLAY 0.617021 (-1463 512);
PAINT WHITE (-1463 512);
FORCEPROP 1 LAST LOCATION R9A17
J 0
(-1425 550);
DISPLAY 0.617021 (-1425 550);
PAINT AQUA (-1425 550);
FORCEPROP 1 LAST PART_NUMBER G21796-026
J 0
(-1225 525);
DISPLAY 0.617021 (-1225 525);
PAINT BLUE (-1225 525);
FORCEPROP 2 LAST CDS_LIB mstr_discrete
J 0
(-1375 500);
DISPLAY 1.617021 (-1375 500);
PAINT MONO (-1375 500);
DISPLAY INVISIBLE (-1375 500);
FORCEPROP 2 LAST ROOM DEBUG
J 0
(-1425 650);
DISPLAY 1.617021 (-1425 650);
PAINT WHITE (-1425 650);
DISPLAY INVISIBLE (-1425 650);
FORCEPROP 2 LAST BOM_COST DEBUG
J 0
(-1425 600);
DISPLAY 1.617021 (-1425 600);
PAINT WHITE (-1425 600);
DISPLAY INVISIBLE (-1425 600);
FORCEPROP 2 LAST SEC_TYPE 0402
J 0
(-1425 600);
DISPLAY 1.659574 (-1425 600);
PAINT ORANGE (-1425 600);
DISPLAY INVISIBLE (-1425 600);
FORCEPROP 1 LAST PATH I57
J 0
(-1425 650);
DISPLAY 0.978723 (-1425 650);
PAINT WHITE (-1425 650);
DISPLAY INVISIBLE (-1425 650);
FORCEPROP 2 LAST CDS_LOCATION R9A17
J 0
(-1425 550);
DISPLAY 0.617021 (-1425 550);
PAINT AQUA (-1425 550);
DISPLAY INVISIBLE (-1425 550);
FORCEPROP 2 LAST SEC 1
J 0
(-1425 700);
DISPLAY 1.510638 (-1425 700);
PAINT MONO (-1425 700);
DISPLAY INVISIBLE (-1425 700);
FORCEADD GND..1
(-1175 800);
FORCEPROP 3 LASTPIN (-1175 850) SIG_NAME GND\g
J 0
(-1165 860);
DISPLAY 0.659574 (-1165 860);
PAINT MONO (-1165 860);
DISPLAY INVISIBLE (-1165 860);
FORCEPROP 2 LAST ROOM CPU_XDP_DEBUG
J 0
(-1625 875);
DISPLAY 1.617021 (-1625 875);
PAINT WHITE (-1625 875);
DISPLAY INVISIBLE (-1625 875);
FORCEPROP 2 LAST BOM_COST DEBUG
J 0
(-1325 875);
DISPLAY 1.617021 (-1325 875);
PAINT WHITE (-1325 875);
DISPLAY INVISIBLE (-1325 875);
FORCEPROP 1 LAST BODY_TYPE PLUMBING
J 0
(-1220 757);
DISPLAY 0.340426 (-1220 757);
PAINT GREEN (-1220 757);
DISPLAY INVISIBLE (-1220 757);
FORCEPROP 1 LAST SIZE 1B
J 0
(-1100 750);
DISPLAY 1.893617 (-1100 750);
PAINT GREEN (-1100 750);
DISPLAY INVISIBLE (-1100 750);
FORCEPROP 1 LAST VOLTAGE 0.0V
J 0
(-1220 757);
DISPLAY 0.340426 (-1220 757);
PAINT SKYBLUE (-1220 757);
DISPLAY INVISIBLE (-1220 757);
FORCEPROP 1 LAST PATH I58
J 0
(-1100 800);
DISPLAY 0.872340 (-1100 800);
PAINT AQUA (-1100 800);
DISPLAY INVISIBLE (-1100 800);
FORCEPROP 2 LAST CDS_LIB mstr_symbols
J 0
(-1175 800);
DISPLAY 2.212766 (-1175 800);
PAINT ORANGE (-1175 800);
DISPLAY INVISIBLE (-1175 800);
FORCEPROP 1 LAST HDL_POWER GND
J 0
(-1175 950);
PAINT GREEN (-1175 950);
DISPLAY INVISIBLE (-1175 950);
FORCEADD CAP_A..1
R 1
(-1475 875);
FORCEPROP 1 LAST VALUE 0.1UF
J 0
(-1825 900);
DISPLAY 0.617021 (-1825 900);
PAINT SKYBLUE (-1825 900);
FORCEPROP 1 LAST TOLERANCE 10%
J 0
(-1625 900);
DISPLAY 0.617021 (-1625 900);
PAINT SKYBLUE (-1625 900);
FORCEPROP 1 LAST VOLTAGE 16V
J 0
(-1700 900);
DISPLAY 0.617021 (-1700 900);
PAINT SKYBLUE (-1700 900);
FORCEPROP 1 LAST PART_NUMBER A36096-030
J 0
(-1600 775);
DISPLAY 0.617021 (-1600 775);
PAINT BLUE (-1600 775);
FORCEPROP 1 LAST LOCATION C9A4
J 0
(-1475 950);
DISPLAY 0.617021 (-1475 950);
PAINT AQUA (-1475 950);
FORCEPROP 1 LASTPIN (-1375 875) $PN 2
J 0
(-1430 885);
DISPLAY 0.617021 (-1430 885);
PAINT WHITE (-1430 885);
FORCEPROP 1 LASTPIN (-1575 875) $PN 1
J 0
(-1530 885);
DISPLAY 0.617021 (-1530 885);
PAINT WHITE (-1530 885);
FORCEPROP 1 LAST MATERIAL X7R
J 0
(-1350 900);
DISPLAY 0.617021 (-1350 900);
PAINT SKYBLUE (-1350 900);
FORCEPROP 1 LAST PACK_TYPE 0402V
J 0
(-1225 900);
DISPLAY 0.617021 (-1225 900);
PAINT SKYBLUE (-1225 900);
FORCEPROP 1 LAST PATH I59
R 1
J 0
(-1625 925);
DISPLAY 0.978723 (-1625 925);
PAINT WHITE (-1625 925);
DISPLAY INVISIBLE (-1625 925);
FORCEPROP 2 LAST SEC_TYPE 0402V
R 1
J 0
(-1475 1000);
DISPLAY 1.659574 (-1475 1000);
PAINT ORANGE (-1475 1000);
DISPLAY INVISIBLE (-1475 1000);
FORCEPROP 2 LAST CDS_LOCATION C9A4
J 0
(-1475 950);
DISPLAY 0.617021 (-1475 950);
PAINT AQUA (-1475 950);
DISPLAY INVISIBLE (-1475 950);
FORCEPROP 2 LAST CDS_LIB dev_discrete
J 0
(-1475 875);
PAINT ORANGE (-1475 875);
DISPLAY INVISIBLE (-1475 875);
FORCEPROP 2 LAST CDS_SEC 1
R 1
J 0
(-1475 1000);
PAINT ORANGE (-1475 1000);
DISPLAY INVISIBLE (-1475 1000);
FORCEPROP 2 LAST ROOM DEBUG
J 0
(-1475 1000);
DISPLAY 1.617021 (-1475 1000);
PAINT WHITE (-1475 1000);
DISPLAY INVISIBLE (-1475 1000);
FORCEPROP 2 LAST BOM_COST DEBUG
J 0
(-1475 1000);
DISPLAY 1.617021 (-1475 1000);
PAINT WHITE (-1475 1000);
DISPLAY INVISIBLE (-1475 1000);
FORCEPROP 2 LAST SEC 1
J 0
(-1475 1000);
DISPLAY 1.510638 (-1475 1000);
PAINT MONO (-1475 1000);
DISPLAY INVISIBLE (-1475 1000);
FORCEADD RES..1
(2725 2150);
FORCEPROP 1 LAST VALUE 1.00K
J 2
(2575 2100);
DISPLAY 0.617021 (2575 2100);
PAINT SKYBLUE (2575 2100);
FORCEPROP 1 LAST WATTAGE 1/16W
J 2
(2700 2100);
DISPLAY 0.617021 (2700 2100);
PAINT SKYBLUE (2700 2100);
FORCEPROP 1 LAST TOLERANCE 1%
J 0
(2725 2100);
DISPLAY 0.617021 (2725 2100);
PAINT SKYBLUE (2725 2100);
FORCEPROP 1 LASTPIN (2625 2150) $PN 1
J 0
(2637 2162);
DISPLAY 0.617021 (2637 2162);
PAINT WHITE (2637 2162);
FORCEPROP 1 LAST LOCATION R1L13
J 0
(2675 2200);
DISPLAY 0.617021 (2675 2200);
PAINT AQUA (2675 2200);
FORCEPROP 1 LASTPIN (2825 2150) $PN 2
J 0
(2787 2162);
DISPLAY 0.617021 (2787 2162);
PAINT WHITE (2787 2162);
FORCEPROP 1 LAST PACK_TYPE 0402
J 0
(2850 2100);
DISPLAY 0.617021 (2850 2100);
PAINT SKYBLUE (2850 2100);
FORCEPROP 1 LAST PART_NUMBER G21796-026
J 0
(2850 2175);
DISPLAY 0.617021 (2850 2175);
PAINT BLUE (2850 2175);
FORCEPROP 1 LAST MATERIAL CHIP
J 0
(2975 2100);
DISPLAY 0.617021 (2975 2100);
PAINT SKYBLUE (2975 2100);
FORCEPROP 2 LAST CDS_LIB mstr_discrete
J 0
(2725 2150);
DISPLAY 2.212766 (2725 2150);
PAINT ORANGE (2725 2150);
DISPLAY INVISIBLE (2725 2150);
FORCEPROP 2 LAST CDS_LOCATION R1L13
J 0
(2675 2200);
DISPLAY 0.617021 (2675 2200);
PAINT AQUA (2675 2200);
DISPLAY INVISIBLE (2675 2200);
FORCEPROP 2 LAST BOM_COST DEBUG
J 0
(2675 2250);
DISPLAY 1.617021 (2675 2250);
PAINT WHITE (2675 2250);
DISPLAY INVISIBLE (2675 2250);
FORCEPROP 2 LAST SEC_TYPE 0402
J 0
(2675 2250);
DISPLAY 1.659574 (2675 2250);
PAINT ORANGE (2675 2250);
DISPLAY INVISIBLE (2675 2250);
FORCEPROP 1 LAST PATH I6
J 0
(2675 2300);
DISPLAY 0.978723 (2675 2300);
PAINT WHITE (2675 2300);
DISPLAY INVISIBLE (2675 2300);
FORCEPROP 2 LAST ROOM DEBUG
J 0
(2675 2300);
DISPLAY 1.617021 (2675 2300);
PAINT WHITE (2675 2300);
DISPLAY INVISIBLE (2675 2300);
FORCEPROP 2 LAST SEC 1
J 0
(2675 2350);
DISPLAY 1.510638 (2675 2350);
PAINT MONO (2675 2350);
DISPLAY INVISIBLE (2675 2350);
FORCEADD RES..1
(-2175 3700);
FORCEPROP 1 LAST VALUE 1.00K
J 2
(-2425 3600);
DISPLAY 0.617021 (-2425 3600);
PAINT SKYBLUE (-2425 3600);
FORCEPROP 1 LAST TOLERANCE 1%
J 0
(-2375 3600);
DISPLAY 0.617021 (-2375 3600);
PAINT SKYBLUE (-2375 3600);
FORCEPROP 1 LAST PART_NUMBER G21796-026
J 0
(-2475 3650);
DISPLAY 0.617021 (-2475 3650);
PAINT BLUE (-2475 3650);
FORCEPROP 1 LASTPIN (-2275 3700) $PN 1
J 0
(-2263 3712);
DISPLAY 0.617021 (-2263 3712);
PAINT WHITE (-2263 3712);
FORCEPROP 1 LAST LOCATION R9A15
J 0
(-2225 3750);
DISPLAY 0.617021 (-2225 3750);
PAINT AQUA (-2225 3750);
FORCEPROP 1 LAST WATTAGE 1/16W
J 2
(-2150 3600);
DISPLAY 0.617021 (-2150 3600);
PAINT SKYBLUE (-2150 3600);
FORCEPROP 1 LASTPIN (-2075 3700) $PN 2
J 0
(-2113 3712);
DISPLAY 0.617021 (-2113 3712);
PAINT WHITE (-2113 3712);
FORCEPROP 1 LAST PACK_TYPE 0402
J 0
(-2125 3650);
DISPLAY 0.617021 (-2125 3650);
PAINT SKYBLUE (-2125 3650);
FORCEPROP 1 LAST MATERIAL CHIP
J 0
(-2075 3600);
DISPLAY 0.617021 (-2075 3600);
PAINT SKYBLUE (-2075 3600);
FORCEPROP 2 LAST CDS_LOCATION R9A15
J 0
(-2225 3750);
DISPLAY 0.617021 (-2225 3750);
PAINT AQUA (-2225 3750);
DISPLAY INVISIBLE (-2225 3750);
FORCEPROP 2 LAST CDS_LIB mstr_discrete
J 0
(-2175 3700);
DISPLAY 2.212766 (-2175 3700);
PAINT ORANGE (-2175 3700);
DISPLAY INVISIBLE (-2175 3700);
FORCEPROP 2 LAST SEC_TYPE 0402
J 0
(-2225 3800);
DISPLAY 1.659574 (-2225 3800);
PAINT ORANGE (-2225 3800);
DISPLAY INVISIBLE (-2225 3800);
FORCEPROP 2 LAST BOM_COST DEBUG
J 0
(-2225 3800);
DISPLAY 1.617021 (-2225 3800);
PAINT WHITE (-2225 3800);
DISPLAY INVISIBLE (-2225 3800);
FORCEPROP 1 LAST PATH I60
J 0
(-2225 3850);
DISPLAY 0.978723 (-2225 3850);
PAINT WHITE (-2225 3850);
DISPLAY INVISIBLE (-2225 3850);
FORCEPROP 2 LAST SEC 1
J 0
(-2225 3900);
DISPLAY 1.510638 (-2225 3900);
PAINT MONO (-2225 3900);
DISPLAY INVISIBLE (-2225 3900);
FORCEPROP 2 LAST ROOM DEBUG
J 0
(-2225 3850);
DISPLAY 1.617021 (-2225 3850);
PAINT WHITE (-2225 3850);
DISPLAY INVISIBLE (-2225 3850);
FORCEADD OFFPAGE..1
(-2875 3700);
FORCEPROP 2 LAST $XR0 190 
J 0
(-3127 3700);
DISPLAY 0.638298 (-3127 3700);
PAINT MONO (-3127 3700);
FORCEPROP 2 LAST $XR1 192 
J 0
(-3247 3700);
DISPLAY 0.638298 (-3247 3700);
PAINT MONO (-3247 3700);
FORCEPROP 2 LAST $XR2 118 
J 0
(-3367 3700);
DISPLAY 0.638298 (-3367 3700);
PAINT MONO (-3367 3700);
FORCEPROP 2 LAST PATH I61
J 0
(-3125 3750);
DISPLAY 1.021277 (-3125 3750);
PAINT ORANGE (-3125 3750);
DISPLAY INVISIBLE (-3125 3750);
FORCEPROP 2 LAST BOM_COST DEBUG
J 0
(-3075 3750);
DISPLAY 1.617021 (-3075 3750);
PAINT WHITE (-3075 3750);
DISPLAY INVISIBLE (-3075 3750);
FORCEPROP 2 LAST ROOM CPU_XDP_DEBUG
J 0
(-3075 3750);
DISPLAY 1.617021 (-3075 3750);
PAINT WHITE (-3075 3750);
DISPLAY INVISIBLE (-3075 3750);
FORCEPROP 2 LAST CDS_LIB mstr_standard
J 0
(-2875 3700);
DISPLAY 2.212766 (-2875 3700);
PAINT ORANGE (-2875 3700);
DISPLAY INVISIBLE (-2875 3700);
FORCEPROP 1 LAST COMMENT_BODY TRUE
J 0
(-2750 3600);
DISPLAY 1.893617 (-2750 3600);
PAINT PEACH (-2750 3600);
DISPLAY INVISIBLE (-2750 3600);
FORCEPROP 1 LAST OFFPAGE TRUE
J 0
(-2550 3575);
PAINT GREEN (-2550 3575);
DISPLAY INVISIBLE (-2550 3575);
FORCEADD OFFPAGE..5
(-2250 500);
FORCEPROP 2 LAST $XR0 118 
J 0
(-2505 500);
DISPLAY 0.638298 (-2505 500);
PAINT MONO (-2505 500);
FORCEPROP 2 LAST $XR1 111 
J 0
(-2625 500);
DISPLAY 0.638298 (-2625 500);
PAINT MONO (-2625 500);
FORCEPROP 1 LAST COMMENT_BODY TRUE
J 0
(-2150 425);
DISPLAY 1.893617 (-2150 425);
PAINT PEACH (-2150 425);
DISPLAY INVISIBLE (-2150 425);
FORCEPROP 2 LAST CDS_LIB mstr_standard
J 1
(-2250 500);
DISPLAY 1.617021 (-2250 500);
PAINT ORANGE (-2250 500);
DISPLAY INVISIBLE (-2250 500);
FORCEPROP 2 LAST PATH I62
J 0
(-2525 550);
DISPLAY 1.021277 (-2525 550);
PAINT ORANGE (-2525 550);
DISPLAY INVISIBLE (-2525 550);
FORCEPROP 2 LAST ROOM CPU_XDP_DEBUG
J 0
(-2450 550);
DISPLAY 1.617021 (-2450 550);
PAINT WHITE (-2450 550);
DISPLAY INVISIBLE (-2450 550);
FORCEPROP 2 LAST BOM_COST DEBUG
J 0
(-2450 550);
DISPLAY 1.617021 (-2450 550);
PAINT WHITE (-2450 550);
DISPLAY INVISIBLE (-2450 550);
FORCEPROP 1 LAST OFFPAGE TRUE
J 0
(-1925 375);
PAINT GREEN (-1925 375);
DISPLAY INVISIBLE (-1925 375);
FORCEADD OFFPAGE..5
(-2325 1425);
FORCEPROP 2 LAST $XR0 111 
J 0
(-2610 1425);
DISPLAY 0.638298 (-2610 1425);
PAINT MONO (-2610 1425);
FORCEPROP 2 LAST $XR1 22 
J 0
(-2700 1425);
DISPLAY 0.638298 (-2700 1425);
PAINT MONO (-2700 1425);
FORCEPROP 2 LAST $XR2 56 
J 0
(-2790 1425);
DISPLAY 0.638298 (-2790 1425);
PAINT MONO (-2790 1425);
FORCEPROP 2 LAST PATH I63
J 0
(-2600 1475);
DISPLAY 1.021277 (-2600 1475);
PAINT ORANGE (-2600 1475);
DISPLAY INVISIBLE (-2600 1475);
FORCEPROP 2 LAST CDS_LIB mstr_standard
J 0
(-2325 1425);
DISPLAY 2.212766 (-2325 1425);
PAINT ORANGE (-2325 1425);
DISPLAY INVISIBLE (-2325 1425);
FORCEPROP 1 LAST COMMENT_BODY TRUE
J 0
(-2225 1350);
DISPLAY 1.893617 (-2225 1350);
PAINT PEACH (-2225 1350);
DISPLAY INVISIBLE (-2225 1350);
FORCEPROP 2 LAST BOM_COST DEBUG
J 0
(-2525 1475);
DISPLAY 1.617021 (-2525 1475);
PAINT WHITE (-2525 1475);
DISPLAY INVISIBLE (-2525 1475);
FORCEPROP 2 LAST ROOM CPU_XDP_DEBUG
J 0
(-2525 1475);
DISPLAY 1.617021 (-2525 1475);
PAINT WHITE (-2525 1475);
DISPLAY INVISIBLE (-2525 1475);
FORCEPROP 1 LAST OFFPAGE TRUE
J 0
(-2000 1300);
PAINT GREEN (-2000 1300);
DISPLAY INVISIBLE (-2000 1300);
FORCEADD OFFPAGE..5
(-2325 1100);
FORCEPROP 2 LAST $XR0 111 
J 0
(-2610 1100);
DISPLAY 0.638298 (-2610 1100);
PAINT MONO (-2610 1100);
FORCEPROP 2 LAST $XR1 118 
J 0
(-2730 1100);
DISPLAY 0.638298 (-2730 1100);
PAINT MONO (-2730 1100);
FORCEPROP 2 LAST $XR2 22 
J 0
(-2820 1100);
DISPLAY 0.638298 (-2820 1100);
PAINT MONO (-2820 1100);
FORCEPROP 2 LAST $XR3 56 
J 0
(-2910 1100);
DISPLAY 0.638298 (-2910 1100);
PAINT MONO (-2910 1100);
FORCEPROP 2 LAST PATH I64
J 0
(-2575 1150);
DISPLAY 1.021277 (-2575 1150);
PAINT ORANGE (-2575 1150);
DISPLAY INVISIBLE (-2575 1150);
FORCEPROP 2 LAST BOM_COST DEBUG
J 0
(-2525 1150);
DISPLAY 1.617021 (-2525 1150);
PAINT WHITE (-2525 1150);
DISPLAY INVISIBLE (-2525 1150);
FORCEPROP 2 LAST ROOM CPU_XDP_DEBUG
J 0
(-2525 1150);
DISPLAY 1.617021 (-2525 1150);
PAINT WHITE (-2525 1150);
DISPLAY INVISIBLE (-2525 1150);
FORCEPROP 2 LAST CDS_LIB mstr_standard
J 1
(-2325 1100);
DISPLAY 1.617021 (-2325 1100);
PAINT ORANGE (-2325 1100);
DISPLAY INVISIBLE (-2325 1100);
FORCEPROP 1 LAST COMMENT_BODY TRUE
J 0
(-2225 1025);
DISPLAY 1.893617 (-2225 1025);
PAINT PEACH (-2225 1025);
DISPLAY INVISIBLE (-2225 1025);
FORCEPROP 1 LAST OFFPAGE TRUE
J 0
(-2000 975);
PAINT GREEN (-2000 975);
DISPLAY INVISIBLE (-2000 975);
FORCEADD P3V3_STBY..1
(3250 2300);
FORCEPROP 3 LASTPIN (3250 2250) SIG_NAME P3V3_STBY\g
J 0
(3260 2260);
DISPLAY 0.659574 (3260 2260);
PAINT MONO (3260 2260);
DISPLAY INVISIBLE (3260 2260);
FORCEPROP 1 LAST HDL_POWER P3V3_STBY
J 0
(2950 2175);
DISPLAY 0.872340 (2950 2175);
PAINT ORANGE (2950 2175);
DISPLAY INVISIBLE (2950 2175);
FORCEPROP 1 LAST BODY_TYPE PLUMBING
J 0
(3205 2257);
DISPLAY 0.340426 (3205 2257);
PAINT GREEN (3205 2257);
DISPLAY INVISIBLE (3205 2257);
FORCEPROP 1 LAST VOLTAGE 3.3V
J 0
(3205 2257);
DISPLAY 0.340426 (3205 2257);
PAINT SKYBLUE (3205 2257);
DISPLAY INVISIBLE (3205 2257);
FORCEPROP 2 LAST CDS_LIB mstr_symbols
J 0
(3250 2300);
PAINT ORANGE (3250 2300);
DISPLAY INVISIBLE (3250 2300);
FORCEPROP 1 LAST PATH I65
J 0
(3295 2302);
DISPLAY 0.340426 (3295 2302);
PAINT GREEN (3295 2302);
DISPLAY INVISIBLE (3295 2302);
FORCEPROP 1 LAST SIZE 1B
J 0
(3295 2322);
DISPLAY 0.340426 (3295 2322);
PAINT GREEN (3295 2322);
DISPLAY INVISIBLE (3295 2322);
FORCEADD RES..2
(2175 2800);
FORCEPROP 1 LASTPIN (2175 2700) $PN 2
J 0
(2180 2710);
DISPLAY 0.617021 (2180 2710);
PAINT ORANGE (2180 2710);
FORCEPROP 1 LAST TOLERANCE 1%
J 0
(2220 2825);
DISPLAY 0.617021 (2220 2825);
PAINT SKYBLUE (2220 2825);
FORCEPROP 1 LASTPIN (2175 2900) $PN 1
J 0
(2180 2862);
DISPLAY 0.617021 (2180 2862);
PAINT ORANGE (2180 2862);
FORCEPROP 1 LAST LOCATION R1L28
J 0
(2220 2925);
DISPLAY 0.617021 (2220 2925);
PAINT AQUA (2220 2925);
FORCEPROP 1 LAST PART_NUMBER G21796-072
J 0
(2215 2675);
DISPLAY 0.617021 (2215 2675);
PAINT BLUE (2215 2675);
FORCEPROP 1 LAST VALUE 4.75K
J 0
(2220 2875);
DISPLAY 0.617021 (2220 2875);
PAINT SKYBLUE (2220 2875);
FORCEPROP 1 LAST PACK_TYPE 0402
J 0
(2215 2625);
DISPLAY 0.617021 (2215 2625);
PAINT SKYBLUE (2215 2625);
FORCEPROP 1 LAST MATERIAL CHIP
J 0
(2215 2725);
DISPLAY 0.617021 (2215 2725);
PAINT SKYBLUE (2215 2725);
FORCEPROP 1 LAST WATTAGE 1/16W
J 0
(2215 2775);
DISPLAY 0.617021 (2215 2775);
PAINT SKYBLUE (2215 2775);
FORCEPROP 2 LAST CDS_LIB mstr_discrete
J 0
(2175 2800);
PAINT ORANGE (2175 2800);
DISPLAY INVISIBLE (2175 2800);
FORCEPROP 2 LAST SEC 1
J 0
(2225 3025);
PAINT MONO (2225 3025);
DISPLAY INVISIBLE (2225 3025);
FORCEPROP 0 LAST ROOM M-SATA
J 0
(2225 3025);
DISPLAY 1.021277 (2225 3025);
PAINT ORANGE (2225 3025);
DISPLAY INVISIBLE (2225 3025);
FORCEPROP 2 LAST SEC_TYPE 0402
J 0
(2225 3025);
DISPLAY 1.021277 (2225 3025);
PAINT ORANGE (2225 3025);
DISPLAY INVISIBLE (2225 3025);
FORCEPROP 1 LAST PATH I66
J 0
(2225 2975);
DISPLAY 0.978723 (2225 2975);
PAINT WHITE (2225 2975);
DISPLAY INVISIBLE (2225 2975);
FORCEPROP 2 LAST CDS_LOCATION R1L28
J 0
(2220 2925);
DISPLAY 0.617021 (2220 2925);
PAINT AQUA (2220 2925);
DISPLAY INVISIBLE (2220 2925);
FORCEPROP 0 LAST BOM_COST M-SATA
J 0
(2225 3125);
DISPLAY 1.021277 (2225 3125);
PAINT ORANGE (2225 3125);
DISPLAY INVISIBLE (2225 3125);
FORCEADD P3V3_STBY..1
(2175 2975);
FORCEPROP 3 LASTPIN (2175 2925) SIG_NAME P3V3_STBY\g
J 0
(2185 2935);
DISPLAY 0.659574 (2185 2935);
PAINT MONO (2185 2935);
DISPLAY INVISIBLE (2185 2935);
FORCEPROP 1 LAST HDL_POWER P3V3_STBY
J 0
(1875 2850);
DISPLAY 0.872340 (1875 2850);
PAINT ORANGE (1875 2850);
DISPLAY INVISIBLE (1875 2850);
FORCEPROP 2 LAST CDS_LIB mstr_symbols
J 0
(2175 2975);
PAINT ORANGE (2175 2975);
DISPLAY INVISIBLE (2175 2975);
FORCEPROP 1 LAST BODY_TYPE PLUMBING
J 0
(2130 2932);
DISPLAY 0.340426 (2130 2932);
PAINT GREEN (2130 2932);
DISPLAY INVISIBLE (2130 2932);
FORCEPROP 1 LAST VOLTAGE 3.3V
J 0
(2130 2932);
DISPLAY 0.340426 (2130 2932);
PAINT SKYBLUE (2130 2932);
DISPLAY INVISIBLE (2130 2932);
FORCEPROP 1 LAST SIZE 1B
J 0
(2220 2997);
DISPLAY 0.340426 (2220 2997);
PAINT GREEN (2220 2997);
DISPLAY INVISIBLE (2220 2997);
FORCEPROP 1 LAST PATH I67
J 0
(2220 2977);
DISPLAY 0.340426 (2220 2977);
PAINT GREEN (2220 2977);
DISPLAY INVISIBLE (2220 2977);
FORCEADD RES..1
(2950 2600);
FORCEPROP 1 LAST WATTAGE 1/16W
J 2
(2925 2450);
DISPLAY 0.617021 (2925 2450);
PAINT SKYBLUE (2925 2450);
FORCEPROP 1 LAST VALUE 33.2
J 2
(2925 2500);
DISPLAY 0.617021 (2925 2500);
PAINT SKYBLUE (2925 2500);
FORCEPROP 1 LAST MATERIAL CHIP
J 0
(2950 2450);
DISPLAY 0.617021 (2950 2450);
PAINT SKYBLUE (2950 2450);
FORCEPROP 1 LAST TOLERANCE 1%
J 0
(2950 2500);
DISPLAY 0.617021 (2950 2500);
PAINT SKYBLUE (2950 2500);
FORCEPROP 1 LASTPIN (2850 2600) $PN 1
J 0
(2862 2612);
DISPLAY 0.617021 (2862 2612);
PAINT ORANGE (2862 2612);
FORCEPROP 1 LAST LOCATION R1L29
J 0
(2900 2650);
DISPLAY 0.617021 (2900 2650);
PAINT AQUA (2900 2650);
FORCEPROP 1 LASTPIN (3050 2600) $PN 2
J 0
(3012 2612);
DISPLAY 0.617021 (3012 2612);
PAINT ORANGE (3012 2612);
FORCEPROP 1 LAST PART_NUMBER G21796-074
J 0
(2900 2700);
DISPLAY 0.617021 (2900 2700);
PAINT BLUE (2900 2700);
FORCEPROP 1 LAST PACK_TYPE 0402
J 0
(3200 2450);
DISPLAY 0.617021 (3200 2450);
PAINT SKYBLUE (3200 2450);
FORCEPROP 1 LAST PATH I68
J 0
(2900 2750);
DISPLAY 0.978723 (2900 2750);
PAINT WHITE (2900 2750);
DISPLAY INVISIBLE (2900 2750);
FORCEPROP 2 LAST CDS_LOCATION R1L29
J 0
(2900 2650);
DISPLAY 0.617021 (2900 2650);
PAINT AQUA (2900 2650);
DISPLAY INVISIBLE (2900 2650);
FORCEPROP 2 LAST CDS_LIB mstr_discrete
J 0
(2950 2600);
PAINT MONO (2950 2600);
DISPLAY INVISIBLE (2950 2600);
FORCEPROP 2 LAST SEC 1
J 0
(2900 2800);
PAINT MONO (2900 2800);
DISPLAY INVISIBLE (2900 2800);
FORCEPROP 2 LAST SEC_TYPE 0402
J 0
(2900 2800);
DISPLAY 1.021277 (2900 2800);
PAINT ORANGE (2900 2800);
DISPLAY INVISIBLE (2900 2800);
FORCEPROP 2 LAST ROOM M-SATA
J 0
(3125 2700);
DISPLAY 1.404255 (3125 2700);
PAINT ORANGE (3125 2700);
DISPLAY INVISIBLE (3125 2700);
FORCEADD P1V05_PCH_STBY..1
(-850 650);
FORCEPROP 3 LASTPIN (-850 600) SIG_NAME P1V05_PCH_STBY\g
J 0
(-840 610);
DISPLAY 0.659574 (-840 610);
PAINT MONO (-840 610);
DISPLAY INVISIBLE (-840 610);
FORCEPROP 1 LAST PATH I69
J 0
(-800 675);
DISPLAY 0.872340 (-800 675);
PAINT AQUA (-800 675);
DISPLAY INVISIBLE (-800 675);
FORCEPROP 1 LAST BODY_TYPE PLUMBING
J 0
(-895 607);
DISPLAY 0.340426 (-895 607);
PAINT GREEN (-895 607);
DISPLAY INVISIBLE (-895 607);
FORCEPROP 2 LAST CDS_LIB mstr_symbols
J 0
(-850 650);
PAINT ORANGE (-850 650);
DISPLAY INVISIBLE (-850 650);
FORCEPROP 1 LAST HDL_POWER P1V05_PCH_STBY
J 0
(-850 700);
DISPLAY 0.872340 (-850 700);
PAINT GREEN (-850 700);
DISPLAY INVISIBLE (-850 700);
FORCEPROP 1 LAST VOLTAGE 1.05V
J 0
(-895 607);
DISPLAY 0.340426 (-895 607);
PAINT SKYBLUE (-895 607);
DISPLAY INVISIBLE (-895 607);
FORCEADD GND..1
(3075 1825);
FORCEPROP 3 LASTPIN (3075 1875) SIG_NAME GND\g
J 0
(3085 1885);
DISPLAY 0.659574 (3085 1885);
PAINT MONO (3085 1885);
DISPLAY INVISIBLE (3085 1885);
FORCEPROP 2 LAST ROOM CPU_XDP_DEBUG
J 0
(2625 1900);
DISPLAY 1.617021 (2625 1900);
PAINT WHITE (2625 1900);
DISPLAY INVISIBLE (2625 1900);
FORCEPROP 1 LAST VOLTAGE 0.0V
J 0
(3030 1782);
DISPLAY 0.340426 (3030 1782);
PAINT SKYBLUE (3030 1782);
DISPLAY INVISIBLE (3030 1782);
FORCEPROP 1 LAST BODY_TYPE PLUMBING
J 0
(3030 1782);
DISPLAY 0.340426 (3030 1782);
PAINT GREEN (3030 1782);
DISPLAY INVISIBLE (3030 1782);
FORCEPROP 2 LAST BOM_COST DEBUG
J 0
(2925 1900);
DISPLAY 1.617021 (2925 1900);
PAINT WHITE (2925 1900);
DISPLAY INVISIBLE (2925 1900);
FORCEPROP 1 LAST SIZE 1B
J 0
(3150 1775);
DISPLAY 1.893617 (3150 1775);
PAINT GREEN (3150 1775);
DISPLAY INVISIBLE (3150 1775);
FORCEPROP 1 LAST HDL_POWER GND
J 0
(3075 1975);
PAINT GREEN (3075 1975);
DISPLAY INVISIBLE (3075 1975);
FORCEPROP 1 LAST PATH I7
J 0
(3150 1825);
DISPLAY 0.872340 (3150 1825);
PAINT AQUA (3150 1825);
DISPLAY INVISIBLE (3150 1825);
FORCEPROP 2 LAST CDS_LIB mstr_symbols
J 0
(3075 1825);
DISPLAY 2.212766 (3075 1825);
PAINT ORANGE (3075 1825);
DISPLAY INVISIBLE (3075 1825);
FORCEADD P1V05_PCH_STBY..1
(750 4750);
FORCEPROP 3 LASTPIN (750 4700) SIG_NAME P1V05_PCH_STBY\g
J 0
(760 4710);
DISPLAY 0.659574 (760 4710);
PAINT MONO (760 4710);
DISPLAY INVISIBLE (760 4710);
FORCEPROP 1 LAST PATH I70
J 0
(800 4775);
DISPLAY 0.872340 (800 4775);
PAINT AQUA (800 4775);
DISPLAY INVISIBLE (800 4775);
FORCEPROP 1 LAST BODY_TYPE PLUMBING
J 0
(705 4707);
DISPLAY 0.340426 (705 4707);
PAINT GREEN (705 4707);
DISPLAY INVISIBLE (705 4707);
FORCEPROP 2 LAST CDS_LIB mstr_symbols
J 0
(750 4750);
PAINT ORANGE (750 4750);
DISPLAY INVISIBLE (750 4750);
FORCEPROP 1 LAST HDL_POWER P1V05_PCH_STBY
J 0
(750 4800);
DISPLAY 0.872340 (750 4800);
PAINT GREEN (750 4800);
DISPLAY INVISIBLE (750 4800);
FORCEPROP 1 LAST VOLTAGE 1.05V
J 0
(705 4707);
DISPLAY 0.340426 (705 4707);
PAINT SKYBLUE (705 4707);
DISPLAY INVISIBLE (705 4707);
FORCEADD P1V05_PCH_STBY..1
(0 4750);
FORCEPROP 3 LASTPIN (0 4700) SIG_NAME P1V05_PCH_STBY\g
J 0
(10 4710);
DISPLAY 0.659574 (10 4710);
PAINT MONO (10 4710);
DISPLAY INVISIBLE (10 4710);
FORCEPROP 1 LAST BODY_TYPE PLUMBING
J 0
(-45 4707);
DISPLAY 0.340426 (-45 4707);
PAINT GREEN (-45 4707);
DISPLAY INVISIBLE (-45 4707);
FORCEPROP 1 LAST VOLTAGE 1.05V
J 0
(-45 4707);
DISPLAY 0.340426 (-45 4707);
PAINT SKYBLUE (-45 4707);
DISPLAY INVISIBLE (-45 4707);
FORCEPROP 1 LAST HDL_POWER P1V05_PCH_STBY
J 0
(0 4800);
DISPLAY 0.872340 (0 4800);
PAINT GREEN (0 4800);
DISPLAY INVISIBLE (0 4800);
FORCEPROP 2 LAST CDS_LIB mstr_symbols
J 0
(0 4750);
PAINT ORANGE (0 4750);
DISPLAY INVISIBLE (0 4750);
FORCEPROP 1 LAST PATH I71
J 0
(50 4775);
DISPLAY 0.872340 (50 4775);
PAINT AQUA (50 4775);
DISPLAY INVISIBLE (50 4775);
FORCEADD RES..1
(-1900 3075);
FORCEPROP 1 LAST WATTAGE 1/16W
J 2
(-2100 3100);
DISPLAY 0.617021 (-2100 3100);
PAINT SKYBLUE (-2100 3100);
FORCEPROP 1 LAST VALUE 0.0
J 2
(-2000 3100);
DISPLAY 0.617021 (-2000 3100);
PAINT SKYBLUE (-2000 3100);
FORCEPROP 1 LAST PART_NUMBER G21497-005
J 0
(-1975 3000);
DISPLAY 0.617021 (-1975 3000);
PAINT BLUE (-1975 3000);
FORCEPROP 1 LASTPIN (-2000 3075) $PN 1
J 0
(-1988 3087);
DISPLAY 0.617021 (-1988 3087);
PAINT ORANGE (-1988 3087);
FORCEPROP 1 LAST LOCATION R9A3
J 0
(-1950 3125);
DISPLAY 0.617021 (-1950 3125);
PAINT AQUA (-1950 3125);
FORCEPROP 1 LASTPIN (-1800 3075) $PN 2
J 0
(-1838 3087);
DISPLAY 0.617021 (-1838 3087);
PAINT ORANGE (-1838 3087);
FORCEPROP 1 LAST TOLERANCE 5%
J 0
(-1750 3100);
DISPLAY 0.617021 (-1750 3100);
PAINT SKYBLUE (-1750 3100);
FORCEPROP 1 LAST PACK_TYPE 0402
J 0
(-1650 3100);
DISPLAY 0.617021 (-1650 3100);
PAINT SKYBLUE (-1650 3100);
FORCEPROP 1 LAST MATERIAL CHIP
J 0
(-1550 3100);
DISPLAY 0.617021 (-1550 3100);
PAINT SKYBLUE (-1550 3100);
FORCEPROP 0 LAST ROOM DEBUG
J 0
(-1950 3275);
DISPLAY 1.021277 (-1950 3275);
PAINT ORANGE (-1950 3275);
DISPLAY INVISIBLE (-1950 3275);
FORCEPROP 2 LAST SEC_TYPE 0402
J 0
(-1950 3275);
DISPLAY 1.021277 (-1950 3275);
PAINT ORANGE (-1950 3275);
DISPLAY INVISIBLE (-1950 3275);
FORCEPROP 2 LAST SEC 1
J 0
(-1950 3275);
DISPLAY 0.680851 (-1950 3275);
PAINT MONO (-1950 3275);
DISPLAY INVISIBLE (-1950 3275);
FORCEPROP 2 LAST CDS_LOCATION R9A3
J 0
(-1950 3125);
DISPLAY 0.617021 (-1950 3125);
PAINT AQUA (-1950 3125);
DISPLAY INVISIBLE (-1950 3125);
FORCEPROP 1 LAST PATH I74
J 0
(-1950 3225);
DISPLAY 0.978723 (-1950 3225);
PAINT WHITE (-1950 3225);
DISPLAY INVISIBLE (-1950 3225);
FORCEPROP 2 LAST CDS_LIB mstr_discrete
J 0
(-1900 3075);
PAINT MONO (-1900 3075);
DISPLAY INVISIBLE (-1900 3075);
FORCEADD OFFPAGE..1
(-3250 3075);
FORCEPROP 2 LAST $XR0 118 
J 0
(-3502 3075);
DISPLAY 0.638298 (-3502 3075);
PAINT MONO (-3502 3075);
FORCEPROP 2 LAST $XR1 112 
J 0
(-3622 3075);
DISPLAY 0.638298 (-3622 3075);
PAINT MONO (-3622 3075);
FORCEPROP 1 LAST COMMENT_BODY TRUE
J 0
(-3125 2975);
DISPLAY 1.893617 (-3125 2975);
PAINT PEACH (-3125 2975);
DISPLAY INVISIBLE (-3125 2975);
FORCEPROP 2 LAST BOM_COST DEBUG
J 0
(-3450 3125);
DISPLAY 1.617021 (-3450 3125);
PAINT WHITE (-3450 3125);
DISPLAY INVISIBLE (-3450 3125);
FORCEPROP 2 LAST ROOM CPU_XDP_DEBUG
J 0
(-3450 3125);
DISPLAY 1.617021 (-3450 3125);
PAINT WHITE (-3450 3125);
DISPLAY INVISIBLE (-3450 3125);
FORCEPROP 2 LAST PATH I75
J 0
(-3200 3150);
DISPLAY 1.021277 (-3200 3150);
PAINT ORANGE (-3200 3150);
DISPLAY INVISIBLE (-3200 3150);
FORCEPROP 2 LAST CDS_LIB mstr_standard
J 0
(-3250 3075);
PAINT MONO (-3250 3075);
DISPLAY INVISIBLE (-3250 3075);
FORCEPROP 1 LAST OFFPAGE TRUE
J 0
(-2925 2950);
PAINT GREEN (-2925 2950);
DISPLAY INVISIBLE (-2925 2950);
FORCEADD GND..1
(3100 1375);
FORCEPROP 3 LASTPIN (3100 1425) SIG_NAME GND\g
J 0
(3110 1435);
DISPLAY 0.659574 (3110 1435);
PAINT MONO (3110 1435);
DISPLAY INVISIBLE (3110 1435);
FORCEPROP 2 LAST ROOM CPU_XDP_DEBUG
J 0
(2650 1450);
DISPLAY 1.617021 (2650 1450);
PAINT WHITE (2650 1450);
DISPLAY INVISIBLE (2650 1450);
FORCEPROP 1 LAST VOLTAGE 0.0V
J 0
(3055 1332);
DISPLAY 0.340426 (3055 1332);
PAINT SKYBLUE (3055 1332);
DISPLAY INVISIBLE (3055 1332);
FORCEPROP 2 LAST BOM_COST DEBUG
J 0
(2950 1450);
DISPLAY 1.617021 (2950 1450);
PAINT WHITE (2950 1450);
DISPLAY INVISIBLE (2950 1450);
FORCEPROP 1 LAST BODY_TYPE PLUMBING
J 0
(3055 1332);
DISPLAY 0.340426 (3055 1332);
PAINT GREEN (3055 1332);
DISPLAY INVISIBLE (3055 1332);
FORCEPROP 2 LAST CDS_LIB mstr_symbols
J 0
(3100 1375);
DISPLAY 2.212766 (3100 1375);
PAINT ORANGE (3100 1375);
DISPLAY INVISIBLE (3100 1375);
FORCEPROP 1 LAST SIZE 1B
J 0
(3175 1325);
DISPLAY 1.893617 (3175 1325);
PAINT GREEN (3175 1325);
DISPLAY INVISIBLE (3175 1325);
FORCEPROP 1 LAST PATH I8
J 0
(3175 1375);
DISPLAY 0.872340 (3175 1375);
PAINT AQUA (3175 1375);
DISPLAY INVISIBLE (3175 1375);
FORCEPROP 1 LAST HDL_POWER GND
J 0
(3100 1525);
PAINT GREEN (3100 1525);
DISPLAY INVISIBLE (3100 1525);
FORCEADD RES..2
(-2925 2675);
FORCEPROP 1 LAST PACK_TYPE 0402
J 0
(-2785 2500);
DISPLAY 0.617021 (-2785 2500);
PAINT SKYBLUE (-2785 2500);
FORCEPROP 1 LASTPIN (-2925 2575) $PN 2
J 0
(-2920 2585);
DISPLAY 0.617021 (-2920 2585);
PAINT ORANGE (-2920 2585);
FORCEPROP 1 LASTPIN (-2925 2775) $PN 1
J 0
(-2920 2737);
DISPLAY 0.617021 (-2920 2737);
PAINT ORANGE (-2920 2737);
FORCEPROP 1 LAST MATERIAL EMPTY
J 0
(-2785 2600);
DISPLAY 0.617021 (-2785 2600);
PAINT RED (-2785 2600);
FORCEPROP 1 LAST LOCATION R9A2
J 0
(-2780 2800);
DISPLAY 0.617021 (-2780 2800);
PAINT AQUA (-2780 2800);
FORCEPROP 1 LAST VALUE 33.2
J 0
(-2780 2750);
DISPLAY 0.617021 (-2780 2750);
PAINT SKYBLUE (-2780 2750);
FORCEPROP 1 LAST TOLERANCE 1%
J 0
(-2780 2700);
DISPLAY 0.617021 (-2780 2700);
PAINT SKYBLUE (-2780 2700);
FORCEPROP 1 LAST WATTAGE 1/16W
J 0
(-2785 2650);
DISPLAY 0.617021 (-2785 2650);
PAINT SKYBLUE (-2785 2650);
FORCEPROP 1 LAST PART_NUMBER G21796-074
J 0
(-2785 2550);
DISPLAY 0.617021 (-2785 2550);
PAINT BLUE (-2785 2550);
FORCEPROP 2 LAST CDS_LIB mstr_discrete
J 0
(-2925 2675);
PAINT ORANGE (-2925 2675);
DISPLAY INVISIBLE (-2925 2675);
FORCEPROP 2 LAST CDS_LOCATION R9A2
J 0
(-2880 2800);
DISPLAY 0.617021 (-2880 2800);
PAINT AQUA (-2880 2800);
DISPLAY INVISIBLE (-2880 2800);
FORCEPROP 0 LAST ROOM DEBUG
J 0
(-2875 2900);
DISPLAY 1.021277 (-2875 2900);
PAINT ORANGE (-2875 2900);
DISPLAY INVISIBLE (-2875 2900);
FORCEPROP 2 LAST SEC_TYPE 0402
J 0
(-2875 2900);
DISPLAY 1.021277 (-2875 2900);
PAINT ORANGE (-2875 2900);
DISPLAY INVISIBLE (-2875 2900);
FORCEPROP 2 LAST SEC 1
J 0
(-2875 2900);
DISPLAY 0.680851 (-2875 2900);
PAINT MONO (-2875 2900);
DISPLAY INVISIBLE (-2875 2900);
FORCEPROP 1 LAST PATH I83
J 0
(-2875 2850);
DISPLAY 0.978723 (-2875 2850);
PAINT WHITE (-2875 2850);
DISPLAY INVISIBLE (-2875 2850);
FORCEADD TTL1G07_A..1
(1775 2600);
FORCEPROP 1 LAST POWER_GROUP VCC=P3V3_STBY;GND=GND
J 1
(1725 2410);
DISPLAY 0.617021 (1725 2410);
PAINT ORANGE (1725 2410);
FORCEPROP 1 LAST PART_NUMBER C88419-001
J 0
(1725 2465);
DISPLAY 0.617021 (1725 2465);
PAINT BLUE (1725 2465);
FORCEPROP 1 LAST MATERIAL IC
J 0
(1725 2750);
DISPLAY 0.617021 (1725 2750);
PAINT SKYBLUE (1725 2750);
FORCEPROP 2 LASTPIN (1675 2600) $PN 2
J 2
(1665 2610);
DISPLAY 0.617021 (1665 2610);
PAINT ORANGE (1665 2610);
FORCEPROP 1 LAST VALUE 74LVC1G07
J 1
(1775 2700);
DISPLAY 0.617021 (1775 2700);
PAINT SKYBLUE (1775 2700);
FORCEPROP 1 LAST LOCATION U1L4
J 0
(1725 2800);
DISPLAY 0.617021 (1725 2800);
PAINT AQUA (1725 2800);
FORCEPROP 2 LASTPIN (1925 2600) $PN 4
J 0
(1935 2610);
DISPLAY 0.617021 (1935 2610);
PAINT ORANGE (1935 2610);
FORCEPROP 0 LAST ROOM M-SATA
J 0
(1725 2900);
DISPLAY 1.021277 (1725 2900);
PAINT ORANGE (1725 2900);
DISPLAY INVISIBLE (1725 2900);
FORCEPROP 0 LAST BOM_COST M-SATA
J 0
(1725 3000);
DISPLAY 1.021277 (1725 3000);
PAINT ORANGE (1725 3000);
DISPLAY INVISIBLE (1725 3000);
FORCEPROP 2 LAST SEC_TYPE SOP
J 0
(1725 2850);
DISPLAY 1.021277 (1725 2850);
PAINT ORANGE (1725 2850);
DISPLAY INVISIBLE (1725 2850);
FORCEPROP 2 LAST SEC 1
J 0
(1725 2850);
DISPLAY 0.680851 (1725 2850);
PAINT MONO (1725 2850);
DISPLAY INVISIBLE (1725 2850);
FORCEPROP 2 LAST CDS_LOCATION U1L4
J 0
(1725 2800);
DISPLAY 0.617021 (1725 2800);
PAINT AQUA (1725 2800);
DISPLAY INVISIBLE (1725 2800);
FORCEPROP 2 LAST CDS_LIB mstr_ttl
J 0
(1775 2600);
PAINT ORANGE (1775 2600);
DISPLAY INVISIBLE (1775 2600);
FORCEPROP 1 LAST PACK_TYPE SOP
J 0
(1725 2850);
DISPLAY 0.978723 (1725 2850);
PAINT SKYBLUE (1725 2850);
DISPLAY INVISIBLE (1725 2850);
FORCEPROP 1 LAST PATH I85
J 0
(1825 2650);
DISPLAY 0.978723 (1825 2650);
PAINT WHITE (1825 2650);
DISPLAY INVISIBLE (1825 2650);
FORCEADD P3V3_STBY..1
(3900 3925);
FORCEPROP 3 LASTPIN (3900 3875) SIG_NAME P3V3_STBY\g
J 0
(3910 3885);
DISPLAY 0.659574 (3910 3885);
PAINT MONO (3910 3885);
DISPLAY INVISIBLE (3910 3885);
FORCEPROP 1 LAST HDL_POWER P3V3_STBY
J 0
(3600 3800);
DISPLAY 0.872340 (3600 3800);
PAINT ORANGE (3600 3800);
DISPLAY INVISIBLE (3600 3800);
FORCEPROP 1 LAST VOLTAGE 3.3V
J 0
(3855 3882);
DISPLAY 0.340426 (3855 3882);
PAINT SKYBLUE (3855 3882);
DISPLAY INVISIBLE (3855 3882);
FORCEPROP 2 LAST CDS_LIB mstr_symbols
J 0
(3900 3925);
PAINT ORANGE (3900 3925);
DISPLAY INVISIBLE (3900 3925);
FORCEPROP 1 LAST SIZE 1B
J 0
(3945 3947);
DISPLAY 0.340426 (3945 3947);
PAINT GREEN (3945 3947);
DISPLAY INVISIBLE (3945 3947);
FORCEPROP 1 LAST BODY_TYPE PLUMBING
J 0
(3855 3882);
DISPLAY 0.340426 (3855 3882);
PAINT GREEN (3855 3882);
DISPLAY INVISIBLE (3855 3882);
FORCEPROP 1 LAST PATH I86
J 0
(3945 3927);
DISPLAY 0.340426 (3945 3927);
PAINT GREEN (3945 3927);
DISPLAY INVISIBLE (3945 3927);
FORCEADD CAP_A..1
(3900 3625);
FORCEPROP 1 LAST PACK_TYPE 0402V
J 0
(3950 3425);
DISPLAY 0.617021 (3950 3425);
PAINT SKYBLUE (3950 3425);
FORCEPROP 1 LAST MATERIAL X7R
J 0
(3950 3525);
DISPLAY 0.617021 (3950 3525);
PAINT SKYBLUE (3950 3525);
FORCEPROP 1 LASTPIN (3900 3525) $PN 2
J 0
(3910 3505);
DISPLAY 0.617021 (3910 3505);
PAINT ORANGE (3910 3505);
FORCEPROP 1 LAST TOLERANCE 10%
J 0
(3950 3575);
DISPLAY 0.617021 (3950 3575);
PAINT SKYBLUE (3950 3575);
FORCEPROP 1 LAST LOCATION C1L11
J 0
(3950 3725);
DISPLAY 0.617021 (3950 3725);
PAINT AQUA (3950 3725);
FORCEPROP 1 LAST VALUE 0.1UF
J 0
(3950 3675);
DISPLAY 0.617021 (3950 3675);
PAINT SKYBLUE (3950 3675);
FORCEPROP 1 LAST VOLTAGE 16V
J 0
(3950 3625);
DISPLAY 0.617021 (3950 3625);
PAINT SKYBLUE (3950 3625);
FORCEPROP 1 LASTPIN (3900 3725) $PN 1
J 0
(3910 3705);
DISPLAY 0.617021 (3910 3705);
PAINT ORANGE (3910 3705);
FORCEPROP 1 LAST PART_NUMBER A36096-030
J 0
(3950 3475);
DISPLAY 0.617021 (3950 3475);
PAINT BLUE (3950 3475);
FORCEPROP 2 LAST ROOM DEBUG
J 0
(3950 3775);
DISPLAY 1.021277 (3950 3775);
PAINT ORANGE (3950 3775);
DISPLAY INVISIBLE (3950 3775);
FORCEPROP 2 LAST CDS_LIB dev_discrete
J 0
(3900 3625);
PAINT ORANGE (3900 3625);
DISPLAY INVISIBLE (3900 3625);
FORCEPROP 2 LAST CDS_SEC 1
J 0
(3950 3775);
PAINT ORANGE (3950 3775);
DISPLAY INVISIBLE (3950 3775);
FORCEPROP 1 LAST PATH I87
J 0
(3950 3775);
DISPLAY 0.978723 (3950 3775);
PAINT WHITE (3950 3775);
DISPLAY INVISIBLE (3950 3775);
FORCEPROP 2 LAST CDS_LOCATION C1L11
J 0
(3950 3725);
DISPLAY 0.617021 (3950 3725);
PAINT AQUA (3950 3725);
DISPLAY INVISIBLE (3950 3725);
FORCEPROP 2 LAST SEC 1
J 0
(3950 3775);
DISPLAY 0.680851 (3950 3775);
PAINT MONO (3950 3775);
DISPLAY INVISIBLE (3950 3775);
FORCEPROP 2 LAST SEC_TYPE 0402V
J 0
(3950 3825);
DISPLAY 1.021277 (3950 3825);
PAINT ORANGE (3950 3825);
DISPLAY INVISIBLE (3950 3825);
FORCEPROP 2 LAST BOM_COST DEBUG
J 0
(3950 3825);
DISPLAY 1.021277 (3950 3825);
PAINT ORANGE (3950 3825);
DISPLAY INVISIBLE (3950 3825);
FORCEADD GND..1
(3900 3325);
FORCEPROP 3 LASTPIN (3900 3375) SIG_NAME GND\g
J 0
(3910 3385);
DISPLAY 0.659574 (3910 3385);
PAINT MONO (3910 3385);
DISPLAY INVISIBLE (3910 3385);
FORCEPROP 1 LAST VOLTAGE 0.0V
J 0
(3855 3282);
DISPLAY 0.340426 (3855 3282);
PAINT SKYBLUE (3855 3282);
DISPLAY INVISIBLE (3855 3282);
FORCEPROP 1 LAST SIZE 1B
J 0
(3975 3275);
DISPLAY 0.872340 (3975 3275);
PAINT AQUA (3975 3275);
DISPLAY INVISIBLE (3975 3275);
FORCEPROP 1 LAST BODY_TYPE PLUMBING
J 0
(3855 3282);
DISPLAY 0.340426 (3855 3282);
PAINT GREEN (3855 3282);
DISPLAY INVISIBLE (3855 3282);
FORCEPROP 2 LAST CDS_LIB mstr_symbols
J 0
(3900 3325);
PAINT ORANGE (3900 3325);
DISPLAY INVISIBLE (3900 3325);
FORCEPROP 1 LAST PATH I88
J 0
(3975 3325);
DISPLAY 0.872340 (3975 3325);
PAINT AQUA (3975 3325);
DISPLAY INVISIBLE (3975 3325);
FORCEPROP 1 LAST HDL_POWER GND
J 0
(3900 3475);
DISPLAY 0.872340 (3900 3475);
PAINT GREEN (3900 3475);
DISPLAY INVISIBLE (3900 3475);
FORCEADD RES..1
(2050 4550);
FORCEPROP 1 LAST VALUE 1.00K
J 2
(2025 4450);
DISPLAY 0.617021 (2025 4450);
PAINT SKYBLUE (2025 4450);
FORCEPROP 1 LAST WATTAGE 1/16W
J 2
(2025 4400);
DISPLAY 0.617021 (2025 4400);
PAINT SKYBLUE (2025 4400);
FORCEPROP 1 LASTPIN (1950 4550) $PN 1
J 0
(1962 4562);
DISPLAY 0.617021 (1962 4562);
PAINT ORANGE (1962 4562);
FORCEPROP 1 LAST LOCATION R8E2
J 0
(2000 4600);
DISPLAY 0.617021 (2000 4600);
PAINT AQUA (2000 4600);
FORCEPROP 1 LAST PART_NUMBER G21796-026
J 0
(2000 4650);
DISPLAY 0.617021 (2000 4650);
PAINT BLUE (2000 4650);
FORCEPROP 1 LAST TOLERANCE 1%
J 0
(2050 4450);
DISPLAY 0.617021 (2050 4450);
PAINT SKYBLUE (2050 4450);
FORCEPROP 1 LASTPIN (2150 4550) $PN 2
J 0
(2112 4562);
DISPLAY 0.617021 (2112 4562);
PAINT ORANGE (2112 4562);
FORCEPROP 1 LAST MATERIAL CHIP
J 0
(2050 4400);
DISPLAY 0.617021 (2050 4400);
PAINT SKYBLUE (2050 4400);
FORCEPROP 1 LAST PACK_TYPE 0402
J 0
(2300 4400);
DISPLAY 0.617021 (2300 4400);
PAINT SKYBLUE (2300 4400);
FORCEPROP 2 LAST CDS_LOCATION R8E2
J 0
(2000 4600);
DISPLAY 0.617021 (2000 4600);
PAINT AQUA (2000 4600);
DISPLAY INVISIBLE (2000 4600);
FORCEPROP 2 LAST ROOM DEBUG
J 0
(2000 4700);
DISPLAY 1.617021 (2000 4700);
PAINT WHITE (2000 4700);
DISPLAY INVISIBLE (2000 4700);
FORCEPROP 2 LAST BOM_COST DEBUG
J 0
(2000 4650);
DISPLAY 1.617021 (2000 4650);
PAINT WHITE (2000 4650);
DISPLAY INVISIBLE (2000 4650);
FORCEPROP 2 LAST SEC_TYPE 0402
J 0
(2000 4750);
DISPLAY 1.021277 (2000 4750);
PAINT ORANGE (2000 4750);
DISPLAY INVISIBLE (2000 4750);
FORCEPROP 2 LAST SEC 1
J 0
(2000 4750);
DISPLAY 0.680851 (2000 4750);
PAINT MONO (2000 4750);
DISPLAY INVISIBLE (2000 4750);
FORCEPROP 1 LAST PATH I89
J 0
(2000 4700);
DISPLAY 0.978723 (2000 4700);
PAINT WHITE (2000 4700);
DISPLAY INVISIBLE (2000 4700);
FORCEPROP 2 LAST CDS_LIB mstr_discrete
J 0
(2050 4550);
PAINT ORANGE (2050 4550);
DISPLAY INVISIBLE (2050 4550);
FORCEADD GND..1
(3125 850);
FORCEPROP 3 LASTPIN (3125 900) SIG_NAME GND\g
J 0
(3135 910);
DISPLAY 0.659574 (3135 910);
PAINT MONO (3135 910);
DISPLAY INVISIBLE (3135 910);
FORCEPROP 2 LAST ROOM CPU_XDP_DEBUG
J 0
(2675 925);
DISPLAY 1.617021 (2675 925);
PAINT WHITE (2675 925);
DISPLAY INVISIBLE (2675 925);
FORCEPROP 2 LAST BOM_COST DEBUG
J 0
(2975 925);
DISPLAY 1.617021 (2975 925);
PAINT WHITE (2975 925);
DISPLAY INVISIBLE (2975 925);
FORCEPROP 1 LAST BODY_TYPE PLUMBING
J 0
(3080 807);
DISPLAY 0.340426 (3080 807);
PAINT GREEN (3080 807);
DISPLAY INVISIBLE (3080 807);
FORCEPROP 2 LAST CDS_LIB mstr_symbols
J 0
(3125 850);
DISPLAY 2.212766 (3125 850);
PAINT ORANGE (3125 850);
DISPLAY INVISIBLE (3125 850);
FORCEPROP 1 LAST VOLTAGE 0.0V
J 0
(3080 807);
DISPLAY 0.340426 (3080 807);
PAINT SKYBLUE (3080 807);
DISPLAY INVISIBLE (3080 807);
FORCEPROP 1 LAST PATH I9
J 0
(3200 850);
DISPLAY 0.872340 (3200 850);
PAINT AQUA (3200 850);
DISPLAY INVISIBLE (3200 850);
FORCEPROP 1 LAST SIZE 1B
J 0
(3200 800);
DISPLAY 1.893617 (3200 800);
PAINT GREEN (3200 800);
DISPLAY INVISIBLE (3200 800);
FORCEPROP 1 LAST HDL_POWER GND
J 0
(3125 1000);
PAINT GREEN (3125 1000);
DISPLAY INVISIBLE (3125 1000);
FORCEADD OFFPAGE..2
(2975 4550);
FORCEPROP 2 LAST $XR0 121 
J 0
(3164 4550);
DISPLAY 0.638298 (3164 4550);
PAINT MONO (3164 4550);
FORCEPROP 2 LAST $XR1 125 
J 0
(3284 4550);
DISPLAY 0.638298 (3284 4550);
PAINT MONO (3284 4550);
FORCEPROP 2 LAST $XR2 154 
J 0
(3404 4550);
DISPLAY 0.638298 (3404 4550);
PAINT MONO (3404 4550);
FORCEPROP 2 LAST $XR3 184 
J 0
(3524 4550);
DISPLAY 0.638298 (3524 4550);
PAINT MONO (3524 4550);
FORCEPROP 1 LAST COMMENT_BODY TRUE
J 0
(2930 4455);
DISPLAY 1.893617 (2930 4455);
PAINT PEACH (2930 4455);
DISPLAY INVISIBLE (2930 4455);
FORCEPROP 2 LAST CDS_LIB mstr_standard
J 0
(2975 4550);
PAINT ORANGE (2975 4550);
DISPLAY INVISIBLE (2975 4550);
FORCEPROP 1 LAST OFFPAGE TRUE
J 0
(3300 4425);
PAINT GREEN (3300 4425);
DISPLAY INVISIBLE (3300 4425);
FORCEPROP 2 LAST BOM_COST DEBUG
J 0
(3350 4600);
DISPLAY 1.617021 (3350 4600);
PAINT WHITE (3350 4600);
DISPLAY INVISIBLE (3350 4600);
FORCEPROP 2 LAST ROOM CPU_XDP_DEBUG
J 0
(3350 4600);
DISPLAY 1.617021 (3350 4600);
PAINT WHITE (3350 4600);
DISPLAY INVISIBLE (3350 4600);
FORCEPROP 2 LAST PATH I90
J 0
(3150 4625);
DISPLAY 1.021277 (3150 4625);
PAINT ORANGE (3150 4625);
DISPLAY INVISIBLE (3150 4625);
FORCEADD OFFPAGE..3
(1875 4150);
FORCEPROP 2 LAST $XR0 112 
J 0
(2089 4150);
DISPLAY 0.638298 (2089 4150);
PAINT MONO (2089 4150);
FORCEPROP 1 LAST COMMENT_BODY TRUE
J 0
(1825 4050);
DISPLAY 0.872340 (1825 4050);
PAINT GREEN (1825 4050);
DISPLAY INVISIBLE (1825 4050);
FORCEPROP 1 LAST OFFPAGE TRUE
J 0
(2200 4025);
DISPLAY 0.872340 (2200 4025);
PAINT GREEN (2200 4025);
DISPLAY INVISIBLE (2200 4025);
FORCEPROP 2 LAST CDS_LIB mstr_standard
J 0
(1875 4150);
PAINT ORANGE (1875 4150);
DISPLAY INVISIBLE (1875 4150);
FORCEPROP 2 LAST BOM_COST DEBUG
J 0
(2250 4200);
DISPLAY 1.617021 (2250 4200);
PAINT WHITE (2250 4200);
DISPLAY INVISIBLE (2250 4200);
FORCEPROP 2 LAST ROOM CPU_XDP_DEBUG
J 0
(2250 4200);
DISPLAY 1.617021 (2250 4200);
PAINT WHITE (2250 4200);
DISPLAY INVISIBLE (2250 4200);
FORCEPROP 2 LAST PATH I91
J 0
(2050 4225);
DISPLAY 1.021277 (2050 4225);
PAINT ORANGE (2050 4225);
DISPLAY INVISIBLE (2050 4225);
FORCEADD OFFPAGE..3
(1875 4100);
FORCEPROP 2 LAST $XR0 112 
J 0
(2089 4100);
DISPLAY 0.638298 (2089 4100);
PAINT MONO (2089 4100);
FORCEPROP 1 LAST COMMENT_BODY TRUE
J 0
(1825 4000);
DISPLAY 0.872340 (1825 4000);
PAINT GREEN (1825 4000);
DISPLAY INVISIBLE (1825 4000);
FORCEPROP 1 LAST OFFPAGE TRUE
J 0
(2200 3975);
DISPLAY 0.872340 (2200 3975);
PAINT GREEN (2200 3975);
DISPLAY INVISIBLE (2200 3975);
FORCEPROP 2 LAST CDS_LIB mstr_standard
J 0
(1875 4100);
PAINT ORANGE (1875 4100);
DISPLAY INVISIBLE (1875 4100);
FORCEPROP 2 LAST BOM_COST DEBUG
J 0
(2250 4150);
DISPLAY 1.617021 (2250 4150);
PAINT WHITE (2250 4150);
DISPLAY INVISIBLE (2250 4150);
FORCEPROP 2 LAST ROOM CPU_XDP_DEBUG
J 0
(2250 4150);
DISPLAY 1.617021 (2250 4150);
PAINT WHITE (2250 4150);
DISPLAY INVISIBLE (2250 4150);
FORCEPROP 2 LAST PATH I92
J 0
(2050 4175);
DISPLAY 1.021277 (2050 4175);
PAINT ORANGE (2050 4175);
DISPLAY INVISIBLE (2050 4175);
FORCEADD NPN_DUAL..2
(-2300 2325);
FORCEPROP 1 LASTPIN (-2400 2275) $PN 1
J 2
(-2400 2285);
DISPLAY 0.617021 (-2400 2285);
PAINT AQUA (-2400 2285);
FORCEPROP 1 LAST LOCATION Q9A1
J 0
(-2425 2400);
DISPLAY 0.617021 (-2425 2400);
PAINT AQUA (-2425 2400);
FORCEPROP 1 LAST PART_NUMBER C52264-001
J 0
(-2400 2150);
DISPLAY 0.617021 (-2400 2150);
PAINT BLUE (-2400 2150);
FORCEPROP 1 LASTPIN (-2200 2275) $PN 6
J 0
(-2165 2285);
DISPLAY 0.617021 (-2165 2285);
PAINT AQUA (-2165 2285);
FORCEPROP 1 LASTPIN (-2300 2425) $PN 2
J 0
(-2295 2410);
DISPLAY 0.617021 (-2295 2410);
PAINT AQUA (-2295 2410);
FORCEPROP 1 LAST MATERIAL EMPTY
J 0
(-2200 2350);
DISPLAY 0.617021 (-2200 2350);
PAINT RED (-2200 2350);
FORCEPROP 1 LAST VALUE MBT3904
J 0
(-2250 2425);
DISPLAY 0.617021 (-2250 2425);
PAINT SKYBLUE (-2250 2425);
FORCEPROP 2 LAST CDS_LOCATION Q9A1
J 0
(-2425 2400);
DISPLAY 0.617021 (-2425 2400);
PAINT AQUA (-2425 2400);
DISPLAY INVISIBLE (-2425 2400);
FORCEPROP 2 LAST CDS_LIB mstr_discrete
J 0
(-2300 2325);
PAINT ORANGE (-2300 2325);
DISPLAY INVISIBLE (-2300 2325);
FORCEPROP 1 LAST PACK_TYPE SSOPLF
J 0
(-2200 2500);
DISPLAY 0.978723 (-2200 2500);
PAINT SKYBLUE (-2200 2500);
DISPLAY INVISIBLE (-2200 2500);
FORCEPROP 2 LAST SEC_TYPE SSOPLF
J 0
(-2200 2500);
DISPLAY 1.021277 (-2200 2500);
PAINT ORANGE (-2200 2500);
DISPLAY INVISIBLE (-2200 2500);
FORCEPROP 2 LAST SEC 2
J 0
(-2200 2500);
DISPLAY 0.680851 (-2200 2500);
PAINT MONO (-2200 2500);
DISPLAY INVISIBLE (-2200 2500);
FORCEPROP 0 LAST ROOM DEBUG
J 0
(-2200 2550);
DISPLAY 1.021277 (-2200 2550);
PAINT ORANGE (-2200 2550);
DISPLAY INVISIBLE (-2200 2550);
FORCEPROP 1 LAST PATH I93
J 0
(-1875 2400);
DISPLAY 0.978723 (-1875 2400);
PAINT BLUE (-1875 2400);
DISPLAY INVISIBLE (-1875 2400);
FORCEADD NPN_DUAL..1
(-1650 2275);
FORCEPROP 1 LASTPIN (-1600 2175) $PN 4
J 2
(-1560 2125);
DISPLAY 0.617021 (-1560 2125);
PAINT AQUA (-1560 2125);
FORCEPROP 1 LASTPIN (-1750 2275) $PN 5
J 0
(-1760 2330);
DISPLAY 0.617021 (-1760 2330);
PAINT AQUA (-1760 2330);
FORCEPROP 1 LAST LOCATION Q9A1
J 0
(-1725 2400);
DISPLAY 0.617021 (-1725 2400);
PAINT AQUA (-1725 2400);
FORCEPROP 1 LASTPIN (-1600 2375) $PN 3
J 0
(-1585 2385);
DISPLAY 0.617021 (-1585 2385);
PAINT AQUA (-1585 2385);
FORCEPROP 1 LAST MATERIAL EMPTY
J 0
(-1475 2225);
DISPLAY 0.617021 (-1475 2225);
PAINT RED (-1475 2225);
FORCEPROP 1 LAST PART_NUMBER C52264-001
J 0
(-1525 2175);
DISPLAY 0.617021 (-1525 2175);
PAINT BLUE (-1525 2175);
FORCEPROP 1 LAST VALUE MBT3904
J 0
(-1475 2275);
DISPLAY 0.617021 (-1475 2275);
PAINT SKYBLUE (-1475 2275);
FORCEPROP 2 LAST CDS_LIB mstr_discrete
J 0
(-1650 2275);
PAINT ORANGE (-1650 2275);
DISPLAY INVISIBLE (-1650 2275);
FORCEPROP 2 LAST CDS_LOCATION Q9A1
J 0
(-1725 2400);
DISPLAY 0.617021 (-1725 2400);
PAINT AQUA (-1725 2400);
DISPLAY INVISIBLE (-1725 2400);
FORCEPROP 1 LAST PACK_TYPE SSOPLF
J 0
(-1550 2425);
DISPLAY 0.978723 (-1550 2425);
PAINT SKYBLUE (-1550 2425);
DISPLAY INVISIBLE (-1550 2425);
FORCEPROP 2 LAST SEC 1
J 0
(-1550 2425);
DISPLAY 0.680851 (-1550 2425);
PAINT MONO (-1550 2425);
DISPLAY INVISIBLE (-1550 2425);
FORCEPROP 2 LAST SEC_TYPE SSOPLF
J 0
(-1550 2425);
DISPLAY 1.021277 (-1550 2425);
PAINT ORANGE (-1550 2425);
DISPLAY INVISIBLE (-1550 2425);
FORCEPROP 0 LAST ROOM DEBUG
J 0
(-1550 2475);
DISPLAY 1.021277 (-1550 2475);
PAINT ORANGE (-1550 2475);
DISPLAY INVISIBLE (-1550 2475);
FORCEPROP 1 LAST PATH I94
J 0
(-1150 2275);
DISPLAY 0.978723 (-1150 2275);
PAINT BLUE (-1150 2275);
DISPLAY INVISIBLE (-1150 2275);
FORCEADD RES..2
R 2
(-2075 2675);
FORCEPROP 1 LAST PACK_TYPE 0402
J 2
(-2115 2550);
DISPLAY 0.617021 (-2115 2550);
PAINT SKYBLUE (-2115 2550);
FORCEPROP 1 LAST PART_NUMBER G21796-026
J 2
(-2215 2575);
DISPLAY 0.617021 (-2215 2575);
PAINT BLUE (-2215 2575);
FORCEPROP 1 LAST WATTAGE 1/16W
J 2
(-2165 2675);
DISPLAY 0.617021 (-2165 2675);
PAINT SKYBLUE (-2165 2675);
FORCEPROP 1 LAST TOLERANCE 1%
J 2
(-2195 2625);
DISPLAY 0.617021 (-2195 2625);
PAINT SKYBLUE (-2195 2625);
FORCEPROP 1 LAST VALUE 1.00K
J 2
(-2145 2725);
DISPLAY 0.617021 (-2145 2725);
PAINT SKYBLUE (-2145 2725);
FORCEPROP 1 LASTPIN (-2075 2575) $PN 2
J 2
(-2080 2585);
DISPLAY 0.617021 (-2080 2585);
PAINT ORANGE (-2080 2585);
FORCEPROP 1 LASTPIN (-2075 2775) $PN 1
J 2
(-2080 2737);
DISPLAY 0.617021 (-2080 2737);
PAINT ORANGE (-2080 2737);
FORCEPROP 1 LAST MATERIAL EMPTY
J 2
(-1840 2725);
DISPLAY 0.617021 (-1840 2725);
PAINT RED (-1840 2725);
FORCEPROP 1 LAST LOCATION R9A1
J 2
(-1895 2650);
DISPLAY 0.617021 (-1895 2650);
PAINT AQUA (-1895 2650);
FORCEPROP 2 LAST CDS_LIB mstr_discrete
J 0
(-2075 2675);
PAINT ORANGE (-2075 2675);
DISPLAY INVISIBLE (-2075 2675);
FORCEPROP 0 LAST ROOM DEBUG
J 2
(-2100 2800);
DISPLAY 1.021277 (-2100 2800);
PAINT ORANGE (-2100 2800);
DISPLAY INVISIBLE (-2100 2800);
FORCEPROP 1 LAST PATH I95
J 2
(-2125 2850);
DISPLAY 0.978723 (-2125 2850);
PAINT WHITE (-2125 2850);
DISPLAY INVISIBLE (-2125 2850);
FORCEPROP 2 LAST SEC 1
J 0
(-2125 2900);
DISPLAY 0.680851 (-2125 2900);
PAINT MONO (-2125 2900);
DISPLAY INVISIBLE (-2125 2900);
FORCEPROP 2 LAST SEC_TYPE 0402
J 0
(-2125 2900);
DISPLAY 1.021277 (-2125 2900);
PAINT ORANGE (-2125 2900);
DISPLAY INVISIBLE (-2125 2900);
FORCEPROP 2 LAST CDS_LOCATION R9A1
J 2
(-1895 2650);
DISPLAY 0.617021 (-1895 2650);
PAINT AQUA (-1895 2650);
DISPLAY INVISIBLE (-1895 2650);
FORCEADD P3V3..1
(-2075 2900);
FORCEPROP 3 LASTPIN (-2075 2850) SIG_NAME P3V3\g
J 0
(-2065 2860);
DISPLAY 0.659574 (-2065 2860);
PAINT MONO (-2065 2860);
DISPLAY INVISIBLE (-2065 2860);
FORCEPROP 1 LAST HDL_POWER P3V3
J 0
(-2400 2775);
DISPLAY 0.872340 (-2400 2775);
PAINT ORANGE (-2400 2775);
DISPLAY INVISIBLE (-2400 2775);
FORCEPROP 1 LAST BODY_TYPE PLUMBING
J 0
(-2120 2857);
DISPLAY 0.340426 (-2120 2857);
PAINT GREEN (-2120 2857);
DISPLAY INVISIBLE (-2120 2857);
FORCEPROP 1 LAST VOLTAGE 3.3V
J 0
(-2120 2857);
DISPLAY 0.340426 (-2120 2857);
PAINT SKYBLUE (-2120 2857);
DISPLAY INVISIBLE (-2120 2857);
FORCEPROP 2 LAST CDS_LIB mstr_symbols
J 0
(-2075 2900);
PAINT ORANGE (-2075 2900);
DISPLAY INVISIBLE (-2075 2900);
FORCEPROP 1 LAST SIZE 1B
J 0
(-2030 2922);
DISPLAY 0.340426 (-2030 2922);
PAINT GREEN (-2030 2922);
DISPLAY INVISIBLE (-2030 2922);
FORCEPROP 1 LAST PATH I96
J 0
(-2030 2902);
DISPLAY 0.340426 (-2030 2902);
PAINT GREEN (-2030 2902);
DISPLAY INVISIBLE (-2030 2902);
FORCEADD DNS..2
(-2295 2320);
PAINT RED (-2295 2320);
FORCEPROP 1 LAST COMMENT_BODY TRUE
R 1
J 0
(-2220 2095);
DISPLAY 0.872340 (-2220 2095);
PAINT GREEN (-2220 2095);
DISPLAY INVISIBLE (-2220 2095);
FORCEPROP 2 LAST CDS_LIB mstr_misc
J 0
(-2295 2320);
PAINT ORANGE (-2295 2320);
DISPLAY INVISIBLE (-2295 2320);
FORCEADD DNS..2
(-2920 2670);
PAINT RED (-2920 2670);
FORCEPROP 1 LAST COMMENT_BODY TRUE
R 1
J 0
(-2845 2445);
DISPLAY 0.872340 (-2845 2445);
PAINT GREEN (-2845 2445);
DISPLAY INVISIBLE (-2845 2445);
FORCEPROP 2 LAST CDS_LIB mstr_misc
J 0
(-2920 2670);
PAINT ORANGE (-2920 2670);
DISPLAY INVISIBLE (-2920 2670);
FORCEADD CAD_NOTE..1
(2875 4900);
FORCEPROP 0 LAST L1 PLACE XDP SERIES R CLSOE TO
J 2
(3125 4775);
DISPLAY 0.638298 (3125 4775);
PAINT ORANGE (3125 4775);
FORCEPROP 0 LAST L2 T POINT WHERE IT CONNECTS TO SPI
J 2
(3125 4700);
DISPLAY 0.638298 (3125 4700);
PAINT ORANGE (3125 4700);
FORCEPROP 2 LAST CDS_LIB mstr_symbols
J 0
(2875 4900);
PAINT ORANGE (2875 4900);
DISPLAY INVISIBLE (2875 4900);
FORCEPROP 1 LAST COMMENT_BODY TRUE
J 0
(2900 5000);
DISPLAY 0.978723 (2900 5000);
PAINT ORANGE (2900 5000);
DISPLAY INVISIBLE (2900 5000);
FORCEADD CAD_NOTE..1
(-2200 2075);
FORCEPROP 0 LAST L1 PLACE BUFFER CIRCUITRY WITHIN 1.1'' OF XDP CONN
J 0
(-3375 1925);
DISPLAY 1.170213 (-3375 1925);
PAINT WHITE (-3375 1925);
FORCEPROP 2 LAST CDS_LIB mstr_symbols
J 0
(-2200 2075);
PAINT MONO (-2200 2075);
DISPLAY INVISIBLE (-2200 2075);
FORCEPROP 1 LAST COMMENT_BODY TRUE
J 0
(-2175 2175);
DISPLAY 2.212766 (-2175 2175);
PAINT PEACH (-2175 2175);
DISPLAY INVISIBLE (-2175 2175);
FORCEADD DNS..2
(-2070 2670);
PAINT RED (-2070 2670);
FORCEPROP 1 LAST COMMENT_BODY TRUE
R 1
J 0
(-1995 2445);
DISPLAY 0.872340 (-1995 2445);
PAINT GREEN (-1995 2445);
DISPLAY INVISIBLE (-1995 2445);
FORCEPROP 2 LAST CDS_LIB mstr_misc
J 0
(-2070 2670);
PAINT ORANGE (-2070 2670);
DISPLAY INVISIBLE (-2070 2670);
FORCEADD CAD_NOTE..1
(3500 3775);
FORCEPROP 0 LAST L1 PLACE 0.1UF CAP NEXT TO VCC PIN
J 2
(3750 3650);
DISPLAY 1.021277 (3750 3650);
PAINT ORANGE (3750 3650);
FORCEPROP 0 LAST L2 ON TTL1G07_A
J 2
(3750 3575);
DISPLAY 1.021277 (3750 3575);
PAINT ORANGE (3750 3575);
FORCEPROP 2 LAST CDS_LIB mstr_symbols
J 0
(3500 3775);
PAINT ORANGE (3500 3775);
DISPLAY INVISIBLE (3500 3775);
FORCEPROP 1 LAST COMMENT_BODY TRUE
J 0
(3525 3875);
DISPLAY 0.978723 (3525 3875);
PAINT ORANGE (3525 3875);
DISPLAY INVISIBLE (3525 3875);
FORCEADD DNS..2
(-1645 2270);
PAINT RED (-1645 2270);
FORCEPROP 1 LAST COMMENT_BODY TRUE
R 1
J 0
(-1570 2045);
DISPLAY 0.872340 (-1570 2045);
PAINT GREEN (-1570 2045);
DISPLAY INVISIBLE (-1570 2045);
FORCEPROP 2 LAST CDS_LIB mstr_misc
J 0
(-1645 2270);
PAINT ORANGE (-1645 2270);
DISPLAY INVISIBLE (-1645 2270);
FORCEADD CAD_NOTE..1
(-2300 4975);
FORCEPROP 0 LAST L2 T POINT WHERE IT CONNECTS TO SPI
J 2
(-2050 4775);
DISPLAY 0.638298 (-2050 4775);
PAINT ORANGE (-2050 4775);
FORCEPROP 0 LAST L1 PLACE XDP SERIES R CLSOE TO
J 2
(-2050 4850);
DISPLAY 0.638298 (-2050 4850);
PAINT ORANGE (-2050 4850);
FORCEPROP 1 LAST COMMENT_BODY TRUE
J 0
(-2275 5075);
DISPLAY 0.978723 (-2275 5075);
PAINT ORANGE (-2275 5075);
DISPLAY INVISIBLE (-2275 5075);
FORCEPROP 2 LAST CDS_LIB mstr_symbols
J 0
(-2300 4975);
PAINT ORANGE (-2300 4975);
DISPLAY INVISIBLE (-2300 4975);
FORCEADD INTEL_CORP_BPAGE..1
(4250 200);
FORCEPROP 1 LAST CDS_CON_LAST_MODIFIED Tue Dec 01 11:51:54 2015
J 0
(2825 525);
PAINT ORANGE (2825 525);
DISPLAY INVISIBLE (2825 525);
FORCEPROP 1 LAST CUSTOM_TXT_CDS <CURRENT_DESIGN_SHEET> OF <TOTAL_DESIGN_SHEETS>
J 0
(3750 225);
PAINT GREEN (3750 225);
FORCEPROP 1 LAST CUSTOM_TXT_CDS <CON_LAST_MODIFIED>
J 0
(2325 550);
PAINT GREEN (2325 550);
FORCEPROP 2 LAST CUSTOM_TXT_CDS <XR_PAGE_TITLE>
J 0
(-3640 5450);
DISPLAY 0.638298 (-3640 5450);
PAINT PINK (-3640 5450);
DISPLAY INVISIBLE (-3640 5450);
FORCEPROP 1 LAST SCH_TITLE CPU & PCH XDP (1-2)
J 0
(-3700 250);
DISPLAY 1.212766 (-3700 250);
PAINT YELLOW (-3700 250);
FORCEPROP 1 LAST SCH_ADDRESS2 P.O. BOX 58119
J 0
(275 275);
DISPLAY 0.617021 (275 275);
PAINT YELLOW (275 275);
FORCEPROP 1 LAST SCH_ADDRESS3 Santa Clara, CA 95052-8119
J 0
(275 225);
DISPLAY 0.617021 (275 225);
PAINT YELLOW (275 225);
FORCEPROP 1 LAST SCH_ADDRESS1 2200 Mission College Blvd.
J 0
(275 325);
DISPLAY 0.617021 (275 325);
PAINT YELLOW (275 325);
FORCEPROP 1 LAST SCH_NUMBER H4694802
J 0
(2950 350);
DISPLAY 1.212766 (2950 350);
PAINT YELLOW (2950 350);
FORCEPROP 1 LAST SCH_DEPT BESD
J 1
(-200 300);
DISPLAY 1.212766 (-200 300);
PAINT YELLOW (-200 300);
FORCEPROP 1 LAST SCH_REV 2.420
J 0
(4000 350);
DISPLAY 0.978723 (4000 350);
PAINT YELLOW (4000 350);
FORCEPROP 2 LAST PAGE_BORDER TRUE
J 0
(-3640 5450);
DISPLAY 0.638298 (-3640 5450);
PAINT PINK (-3640 5450);
DISPLAY INVISIBLE (-3640 5450);
FORCEPROP 2 LAST CDS_LIB mstr_symbols
J 0
(4250 200);
PAINT MONO (4250 200);
DISPLAY INVISIBLE (4250 200);
FORCEPROP 1 LAST COMMENT_BODY TRUE
J 0
(4262 212);
DISPLAY 0.468085 (4262 212);
PAINT PEACH (4262 212);
DISPLAY INVISIBLE (4262 212);
FORCEPROP 2 LAST CDS_XR_PAGE_TITLE CR-111 : @BASEBOARD_FAB2_LIB.BASEBOARD_FAB2(SCH_1):PAGE111
J 0
(-3640 5450);
DISPLAY 0.638298 (-3640 5450);
PAINT PINK (-3640 5450);
DISPLAY INVISIBLE (-3640 5450);
WIRE 16 -1 (500 4650)(875 4650);
WIRE 16 -1 (875 4650)(875 4500);
WIRE 16 -1 (500 4500)(875 4500);
WIRE 16 -1 (875 4500)(875 4350);
WIRE 16 -1 (500 4350)(875 4350);
WIRE 16 -1 (875 4200)(875 4350);
WIRE 16 -1 (500 4200)(875 4200);
WIRE 16 -1 (875 4200)(875 4050);
WIRE 16 -1 (500 4050)(875 4050);
WIRE 16 -1 (875 4050)(875 3900);
WIRE 16 -1 (500 3900)(875 3900);
WIRE 16 -1 (875 3900)(875 3750);
WIRE 16 -1 (500 3750)(875 3750);
WIRE 16 -1 (875 3750)(875 3450);
WIRE 16 -1 (500 3450)(875 3450);
WIRE 16 -1 (875 3450)(875 2775);
WIRE 16 -1 (750 2775)(875 2775);
WIRE 16 -1 (875 2775)(875 2675);
WIRE 16 -1 (750 2825)(750 2775);
WIRE 16 -1 (200 4500)(-100 4500);
WIRE 16 -1 (-100 4500)(-100 4350);
WIRE 16 -1 (200 4350)(-100 4350);
WIRE 16 -1 (-100 4350)(-100 4200);
WIRE 16 -1 (200 4200)(-100 4200);
WIRE 16 -1 (-100 4200)(-100 4050);
WIRE 16 -1 (200 4050)(-100 4050);
WIRE 16 -1 (-100 4050)(-100 3900);
WIRE 16 -1 (200 3900)(-100 3900);
WIRE 16 -1 (-100 3900)(-100 3750);
WIRE 16 -1 (200 3750)(-100 3750);
WIRE 16 -1 (-100 3750)(-100 3450);
WIRE 16 -1 (200 3450)(-100 3450);
WIRE 16 -1 (-100 3450)(-100 3200);
WIRE 16 -1 (200 3200)(-100 3200);
WIRE 16 -1 (-100 2775)(-100 3200);
WIRE 16 -1 (0 2775)(-100 2775);
WIRE 16 -1 (-100 2675)(-100 2775);
WIRE 16 -1 (0 2825)(0 2775);
WIRE 16 -1 (-1375 1100)(-925 1100);
WIRE 16 -1 (-925 1100)(-925 1425);
WIRE 16 -1 (-1375 1425)(-925 1425);
WIRE 16 -1 (-925 1550)(-925 1425);
WIRE 16 -1 (-1375 875)(-1175 875);
WIRE 16 -1 (-1175 850)(-1175 875);
WIRE 16 -1 (2825 1125)(3250 1125);
WIRE 16 -1 (3250 1125)(3250 1700);
WIRE 16 -1 (2825 1700)(3250 1700);
WIRE 16 -1 (3250 2150)(3250 1700);
WIRE 16 -1 (2825 2150)(3250 2150);
WIRE 16 -1 (3250 2150)(3250 2250);
WIRE 16 -1 (2175 2900)(2175 2925);
WIRE 16 -1 (-1275 500)(-850 500);
WIRE 16 -1 (-850 600)(-850 500);
WIRE 16 -1 (2850 1900)(3075 1900);
WIRE 16 -1 (3075 1875)(3075 1900);
WIRE 16 -1 (750 3025)(750 3600);
WIRE 16 -1 (750 4700)(750 3600);
WIRE 16 -1 (500 3600)(750 3600);
WIRE 16 -1 (0 3600)(0 3025);
WIRE 16 -1 (200 3600)(0 3600);
WIRE 16 -1 (0 4700)(0 3600);
WIRE 16 -1 (2900 1450)(3100 1450);
WIRE 16 -1 (3100 1425)(3100 1450);
WIRE 16 -1 (3900 3875)(3900 3725);
WIRE 16 -1 (3900 3375)(3900 3525);
WIRE 16 -1 (2925 925)(3125 925);
WIRE 16 -1 (3125 900)(3125 925);
WIRE 16 -1 (-1600 2375)(-1600 2825);
WIRE 16 -1 (-1600 2825)(-2075 2825);
WIRE 16 -1 (-2075 2775)(-2075 2825);
WIRE 16 -1 (-2075 2825)(-2075 2850);
WIRE 16 -1 (2150 4550)(2925 4550);
FORCEPROP 0 LAST SIG_NAME SPI_PCH_MOSI
J 0
(2540 4560);
DISPLAY 0.617021 (2540 4560);
PAINT ORANGE (2540 4560);
WIRE 16 -1 (1825 4300)(500 4300);
FORCEPROP 2 LAST SIG_NAME TP_XDP_CPU_OBSDATA_C2
J 0
(990 4310);
DISPLAY 0.617021 (990 4310);
PAINT ORANGE (990 4310);
FORCEPROP 2 LASTPROP $XRERR UNIQUE?
J 0
(1855 4300);
DISPLAY 0.638298 (1855 4300);
PAINT MONO (1855 4300);
DISPLAY INVISIBLE (1855 4300);
WIRE 16 -1 (1825 4250)(500 4250);
FORCEPROP 2 LAST SIG_NAME TP_XDP_CPU_OBSDATA_C3
J 0
(990 4260);
DISPLAY 0.617021 (990 4260);
PAINT ORANGE (990 4260);
FORCEPROP 2 LASTPROP $XRERR UNIQUE?
J 0
(1855 4250);
DISPLAY 0.638298 (1855 4250);
PAINT MONO (1855 4250);
DISPLAY INVISIBLE (1855 4250);
WIRE 16 -1 (1825 4450)(500 4450);
FORCEPROP 2 LAST SIG_NAME TP_XDP_CPU_OBSDATA_C0
J 0
(990 4460);
DISPLAY 0.617021 (990 4460);
PAINT ORANGE (990 4460);
FORCEPROP 2 LASTPROP $XRERR UNIQUE?
J 0
(1855 4450);
DISPLAY 0.638298 (1855 4450);
PAINT MONO (1855 4450);
DISPLAY INVISIBLE (1855 4450);
WIRE 16 -1 (1825 4400)(500 4400);
FORCEPROP 2 LAST SIG_NAME TP_XDP_CPU_OBSDATA_C1
J 0
(990 4410);
DISPLAY 0.617021 (990 4410);
PAINT ORANGE (990 4410);
FORCEPROP 2 LASTPROP $XRERR UNIQUE?
J 0
(1855 4400);
DISPLAY 0.638298 (1855 4400);
PAINT MONO (1855 4400);
DISPLAY INVISIBLE (1855 4400);
WIRE 16 -1 (500 4550)(1950 4550);
FORCEPROP 2 LAST SIG_NAME XDP_SPI_PCH_MOSI_BOOT_HALT_N
J 0
(990 4560);
DISPLAY 0.617021 (990 4560);
PAINT ORANGE (990 4560);
FORCEPROP 2 LASTPROP $XRERR UNIQUE?
J 0
(750 4560);
DISPLAY 0.638298 (750 4560);
PAINT MONO (750 4560);
DISPLAY INVISIBLE (750 4560);
WIRE 16 -1 (1825 4600)(500 4600);
FORCEPROP 2 LAST SIG_NAME TP_XDP_CPU_OBSFN_C0
J 0
(990 4610);
DISPLAY 0.617021 (990 4610);
PAINT ORANGE (990 4610);
FORCEPROP 2 LASTPROP $XRERR UNIQUE?
J 0
(1855 4600);
DISPLAY 0.638298 (1855 4600);
PAINT MONO (1855 4600);
DISPLAY INVISIBLE (1855 4600);
WIRE 16 -1 (1825 4100)(500 4100);
FORCEPROP 2 LAST SIG_NAME XDP_OBSFN_B1_MBP7_N
J 0
(990 4110);
DISPLAY 0.617021 (990 4110);
PAINT ORANGE (990 4110);
WIRE 16 -1 (1825 4150)(500 4150);
FORCEPROP 2 LAST SIG_NAME XDP_OBSFN_B0_MBP6_N
J 0
(990 4160);
DISPLAY 0.617021 (990 4160);
PAINT ORANGE (990 4160);
WIRE 16 -1 (3050 2600)(3525 2600);
FORCEPROP 2 LAST SIG_NAME FM_DEBUG_RST_BTN_N
J 0
(3090 2610);
DISPLAY 0.617021 (3090 2610);
PAINT ORANGE (3090 2610);
WIRE 16 -1 (2425 2150)(2625 2150);
WIRE 16 -1 (2425 1900)(2425 2150);
WIRE 16 -1 (2025 2150)(2425 2150);
FORCEPROP 2 LAST SIG_NAME XDP_SYSPWROK
J 2
(2365 2160);
DISPLAY 0.617021 (2365 2160);
PAINT ORANGE (2365 2160);
WIRE 16 -1 (2650 1900)(2425 1900);
WIRE 16 -1 (2175 2700)(2175 2600);
WIRE 16 -1 (2850 2600)(2175 2600);
FORCEPROP 2 LAST SIG_NAME FM_DEBUG_RST_BTN_R1_N
J 0
(2340 2610);
DISPLAY 0.617021 (2340 2610);
PAINT ORANGE (2340 2610);
FORCEPROP 2 LASTPROP $XRERR UNIQUE?
J 0
(2100 2610);
DISPLAY 0.638298 (2100 2610);
PAINT MONO (2100 2610);
DISPLAY INVISIBLE (2100 2610);
WIRE 16 -1 (1925 2600)(2175 2600);
WIRE 16 -1 (2050 1125)(2450 1125);
FORCEPROP 2 LAST SIG_NAME XDP_PWRGD_RST_N
J 0
(2065 1135);
DISPLAY 0.617021 (2065 1135);
PAINT ORANGE (2065 1135);
WIRE 16 -1 (2450 1125)(2625 1125);
WIRE 16 -1 (2450 925)(2450 1125);
WIRE 16 -1 (2725 925)(2450 925);
WIRE 16 -1 (2700 1450)(2425 1450);
WIRE 16 -1 (2425 1450)(2425 1700);
WIRE 16 -1 (2425 1700)(2625 1700);
WIRE 16 -1 (2025 1700)(2425 1700);
FORCEPROP 2 LAST SIG_NAME XDP_RST_CO_N
J 0
(2040 1710);
DISPLAY 0.617021 (2040 1710);
PAINT ORANGE (2040 1710);
WIRE 16 -1 (1350 3500)(2800 3500);
WIRE 16 -1 (1350 3500)(1350 2600);
WIRE 16 -1 (500 3500)(1350 3500);
FORCEPROP 2 LAST SIG_NAME XDP_RST_CO_N
J 0
(990 3510);
DISPLAY 0.617021 (990 3510);
PAINT ORANGE (990 3510);
WIRE 16 -1 (1675 2600)(1350 2600);
WIRE 16 -1 (1825 3800)(500 3800);
FORCEPROP 2 LAST SIG_NAME TP_XDP_CPU_OBSDATA_D3
J 0
(990 3810);
DISPLAY 0.617021 (990 3810);
PAINT ORANGE (990 3810);
FORCEPROP 2 LASTPROP $XRERR UNIQUE?
J 0
(1855 3800);
DISPLAY 0.638298 (1855 3800);
PAINT MONO (1855 3800);
DISPLAY INVISIBLE (1855 3800);
WIRE 16 -1 (1825 3950)(500 3950);
FORCEPROP 2 LAST SIG_NAME TP_XDP_CPU_OBSDATA_D1
J 0
(990 3960);
DISPLAY 0.617021 (990 3960);
PAINT ORANGE (990 3960);
FORCEPROP 2 LASTPROP $XRERR UNIQUE?
J 0
(1855 3950);
DISPLAY 0.638298 (1855 3950);
PAINT MONO (1855 3950);
DISPLAY INVISIBLE (1855 3950);
WIRE 16 -1 (1825 3850)(500 3850);
FORCEPROP 2 LAST SIG_NAME TP_XDP_CPU_OBSDATA_D2
J 0
(990 3860);
DISPLAY 0.617021 (990 3860);
PAINT ORANGE (990 3860);
FORCEPROP 2 LASTPROP $XRERR UNIQUE?
J 0
(1855 3850);
DISPLAY 0.638298 (1855 3850);
PAINT MONO (1855 3850);
DISPLAY INVISIBLE (1855 3850);
WIRE 16 -1 (1825 4000)(500 4000);
FORCEPROP 2 LAST SIG_NAME TP_XDP_CPU_OBSDATA_D0
J 0
(990 4010);
DISPLAY 0.617021 (990 4010);
PAINT ORANGE (990 4010);
FORCEPROP 2 LASTPROP $XRERR UNIQUE?
J 0
(1855 4000);
DISPLAY 0.638298 (1855 4000);
PAINT MONO (1855 4000);
DISPLAY INVISIBLE (1855 4000);
WIRE 16 -1 (1825 3200)(500 3200);
FORCEPROP 2 LAST SIG_NAME XDP_PRESENT_N
J 0
(990 3210);
DISPLAY 0.617021 (990 3210);
PAINT ORANGE (990 3210);
WIRE 16 -1 (1825 3250)(500 3250);
FORCEPROP 2 LAST SIG_NAME XDP_TMS
J 0
(990 3260);
DISPLAY 0.617021 (990 3260);
PAINT ORANGE (990 3260);
WIRE 16 -1 (1825 3350)(500 3350);
FORCEPROP 2 LAST SIG_NAME XDP_TRST_N
J 0
(990 3360);
DISPLAY 0.617021 (990 3360);
PAINT ORANGE (990 3360);
WIRE 16 -1 (1825 3300)(500 3300);
FORCEPROP 2 LAST SIG_NAME XDP_TDI
J 0
(990 3310);
DISPLAY 0.617021 (990 3310);
PAINT ORANGE (990 3310);
WIRE 16 -1 (1825 3400)(500 3400);
FORCEPROP 2 LAST SIG_NAME XDP_TDO
J 0
(990 3410);
DISPLAY 0.617021 (990 3410);
PAINT ORANGE (990 3410);
WIRE 16 -1 (1825 3550)(500 3550);
FORCEPROP 2 LAST SIG_NAME XDP_ITP_PMODE
J 0
(990 3560);
DISPLAY 0.617021 (990 3560);
PAINT ORANGE (990 3560);
WIRE 16 -1 (1825 3650)(500 3650);
FORCEPROP 2 LAST SIG_NAME CLK_100M_PCH_XDP_DN
J 0
(975 3651);
DISPLAY 0.617021 (975 3651);
PAINT ORANGE (975 3651);
WIRE 16 -1 (1825 3700)(500 3700);
FORCEPROP 2 LAST SIG_NAME CLK_100M_PCH_XDP_DP
J 0
(975 3701);
DISPLAY 0.617021 (975 3701);
PAINT ORANGE (975 3701);
WIRE 16 -1 (200 3250)(-625 3250);
WIRE 16 -1 (-625 3250)(-625 3075);
WIRE 16 -1 (-625 3250)(-1125 3250);
FORCEPROP 2 LAST SIG_NAME XDP_CPU_TCK0
J 0
(-985 3260);
DISPLAY 0.617021 (-985 3260);
PAINT ORANGE (-985 3260);
WIRE 16 -1 (-625 3075)(-1250 3075);
WIRE 16 -1 (-1800 3075)(-1250 3075);
WIRE 16 -1 (-1250 3075)(-1250 2075);
WIRE 16 -1 (-1250 2075)(-1600 2075);
WIRE 16 -1 (-1600 2075)(-1600 2175);
WIRE 16 -1 (-2150 4650)(200 4650);
FORCEPROP 2 LAST SIG_NAME XDP_DEBUG_CONSENT_N
J 0
(-985 4660);
DISPLAY 0.617021 (-985 4660);
PAINT ORANGE (-985 4660);
FORCEPROP 2 LASTPROP $XRERR UNIQUE?
J 0
(-1225 4660);
DISPLAY 0.638298 (-1225 4660);
PAINT MONO (-1225 4660);
DISPLAY INVISIBLE (-1225 4660);
WIRE 16 -1 (200 3700)(-2075 3700);
FORCEPROP 2 LAST SIG_NAME XDP_RSMRST_N
J 0
(-985 3710);
DISPLAY 0.617021 (-985 3710);
PAINT ORANGE (-985 3710);
FORCEPROP 2 LASTPROP $XRERR UNIQUE?
J 0
(-1225 3710);
DISPLAY 0.638298 (-1225 3710);
PAINT MONO (-1225 3710);
DISPLAY INVISIBLE (-1225 3710);
WIRE 16 -1 (200 3850)(-1125 3850);
FORCEPROP 2 LAST SIG_NAME TP_XDP_OBSDATA_B2
J 0
(-985 3860);
DISPLAY 0.617021 (-985 3860);
PAINT ORANGE (-985 3860);
FORCEPROP 2 LASTPROP $XRERR UNIQUE?
J 0
(-1365 3850);
DISPLAY 0.638298 (-1365 3850);
PAINT MONO (-1365 3850);
DISPLAY INVISIBLE (-1365 3850);
WIRE 16 -1 (200 3800)(-1125 3800);
FORCEPROP 2 LAST SIG_NAME TP_XDP_OBSDATA_B3
J 0
(-985 3810);
DISPLAY 0.617021 (-985 3810);
PAINT ORANGE (-985 3810);
FORCEPROP 2 LASTPROP $XRERR UNIQUE?
J 0
(-1365 3800);
DISPLAY 0.638298 (-1365 3800);
PAINT MONO (-1365 3800);
DISPLAY INVISIBLE (-1365 3800);
WIRE 16 -1 (200 3950)(-1125 3950);
FORCEPROP 2 LAST SIG_NAME TP_XDP_OBSDATA_B1
J 0
(-985 3960);
DISPLAY 0.617021 (-985 3960);
PAINT ORANGE (-985 3960);
FORCEPROP 2 LASTPROP $XRERR UNIQUE?
J 0
(-1365 3950);
DISPLAY 0.638298 (-1365 3950);
PAINT MONO (-1365 3950);
DISPLAY INVISIBLE (-1365 3950);
WIRE 16 -1 (200 4000)(-1125 4000);
FORCEPROP 2 LAST SIG_NAME TP_XDP_OBSDATA_B0
J 0
(-985 4010);
DISPLAY 0.617021 (-985 4010);
PAINT ORANGE (-985 4010);
FORCEPROP 2 LASTPROP $XRERR UNIQUE?
J 0
(-1365 4000);
DISPLAY 0.638298 (-1365 4000);
PAINT MONO (-1365 4000);
DISPLAY INVISIBLE (-1365 4000);
WIRE 16 -1 (200 4100)(-1125 4100);
FORCEPROP 0 LAST SIG_NAME TP_XDP_OBSFN_B1
J 0
(-985 4110);
DISPLAY 0.617021 (-985 4110);
PAINT ORANGE (-985 4110);
FORCEPROP 2 LASTPROP $XRERR UNIQUE?
J 0
(-1365 4100);
DISPLAY 0.638298 (-1365 4100);
PAINT MONO (-1365 4100);
DISPLAY INVISIBLE (-1365 4100);
WIRE 16 -1 (200 4150)(-1125 4150);
FORCEPROP 0 LAST SIG_NAME TP_XDP_OBSFN_B0
J 0
(-985 4160);
DISPLAY 0.617021 (-985 4160);
PAINT ORANGE (-985 4160);
FORCEPROP 2 LASTPROP $XRERR UNIQUE?
J 0
(-1365 4150);
DISPLAY 0.638298 (-1365 4150);
PAINT MONO (-1365 4150);
DISPLAY INVISIBLE (-1365 4150);
WIRE 16 -1 (-1125 4250)(200 4250);
FORCEPROP 2 LAST SIG_NAME TP_XDP_OBSDATA_A3
J 0
(-1085 4260);
DISPLAY 0.617021 (-1085 4260);
PAINT ORANGE (-1085 4260);
FORCEPROP 2 LASTPROP $XRERR UNIQUE?
J 0
(-1365 4250);
DISPLAY 0.638298 (-1365 4250);
PAINT MONO (-1365 4250);
DISPLAY INVISIBLE (-1365 4250);
WIRE 16 -1 (200 4300)(-1125 4300);
FORCEPROP 2 LAST SIG_NAME TP_XDP_OBSDATA_A2
J 0
(-1085 4310);
DISPLAY 0.617021 (-1085 4310);
PAINT ORANGE (-1085 4310);
FORCEPROP 2 LASTPROP $XRERR UNIQUE?
J 0
(-1365 4300);
DISPLAY 0.638298 (-1365 4300);
PAINT MONO (-1365 4300);
DISPLAY INVISIBLE (-1365 4300);
WIRE 16 -1 (-1125 4400)(200 4400);
FORCEPROP 2 LAST SIG_NAME TP_XDP_OBSDATA_A1
J 0
(-1085 4410);
DISPLAY 0.617021 (-1085 4410);
PAINT ORANGE (-1085 4410);
FORCEPROP 2 LASTPROP $XRERR UNIQUE?
J 0
(-1365 4400);
DISPLAY 0.638298 (-1365 4400);
PAINT MONO (-1365 4400);
DISPLAY INVISIBLE (-1365 4400);
WIRE 16 -1 (200 4450)(-1125 4450);
FORCEPROP 2 LAST SIG_NAME TP_XDP_OBSDATA_A0
J 0
(-1085 4460);
DISPLAY 0.617021 (-1085 4460);
PAINT ORANGE (-1085 4460);
FORCEPROP 2 LASTPROP $XRERR UNIQUE?
J 0
(-1365 4450);
DISPLAY 0.638298 (-1365 4450);
PAINT MONO (-1365 4450);
DISPLAY INVISIBLE (-1365 4450);
WIRE 16 -1 (200 3350)(-1125 3350);
FORCEPROP 2 LAST SIG_NAME SMB_HOST_STBY_LVC3_SCL
J 0
(-985 3360);
DISPLAY 0.617021 (-985 3360);
PAINT ORANGE (-985 3360);
WIRE 16 -1 (200 3300)(-1125 3300);
FORCEPROP 2 LAST SIG_NAME XDP_PCH_TCK1
J 0
(-985 3310);
DISPLAY 0.617021 (-985 3310);
PAINT ORANGE (-985 3310);
WIRE 16 -1 (200 3400)(-1125 3400);
FORCEPROP 2 LAST SIG_NAME SMB_HOST_STBY_LVC3_SDA
J 0
(-985 3410);
DISPLAY 0.617021 (-985 3410);
PAINT ORANGE (-985 3410);
WIRE 16 -1 (200 3500)(-1125 3500);
FORCEPROP 2 LAST SIG_NAME XDP_SYSPWROK
J 2
(-685 3510);
DISPLAY 0.617021 (-685 3510);
PAINT ORANGE (-685 3510);
WIRE 16 -1 (200 3550)(-1125 3550);
FORCEPROP 2 LAST SIG_NAME XDP_CPU_PWR_DEBUG_N
J 0
(-985 3560);
DISPLAY 0.617021 (-985 3560);
PAINT ORANGE (-985 3560);
WIRE 16 -1 (200 3650)(-1125 3650);
FORCEPROP 2 LAST SIG_NAME XDP_PWRGD_RST_N
J 0
(-985 3660);
DISPLAY 0.617021 (-985 3660);
PAINT ORANGE (-985 3660);
WIRE 16 -1 (-1125 4550)(200 4550);
FORCEPROP 2 LAST SIG_NAME XDP_PRDY_N
J 0
(-985 4560);
DISPLAY 0.617021 (-985 4560);
PAINT ORANGE (-985 4560);
WIRE 16 -1 (-1125 4600)(200 4600);
FORCEPROP 2 LAST SIG_NAME XDP_PREQ_N
J 0
(-985 4610);
DISPLAY 0.617021 (-985 4610);
PAINT ORANGE (-985 4610);
WIRE 16 -1 (-2900 4650)(-2350 4650);
FORCEPROP 2 LAST SIG_NAME SPI_PCH_IO2
J 2
(-2585 4660);
DISPLAY 0.617021 (-2585 4660);
PAINT ORANGE (-2585 4660);
WIRE 16 -1 (-1850 1100)(-1575 1100);
WIRE 16 -1 (-1850 875)(-1850 1100);
WIRE 16 -1 (-2275 1100)(-1850 1100);
FORCEPROP 2 LAST SIG_NAME XDP_CPU_PWR_DEBUG_N
J 0
(-2235 1110);
DISPLAY 0.617021 (-2235 1110);
PAINT ORANGE (-2235 1110);
WIRE 16 -1 (-1575 875)(-1850 875);
WIRE 16 -1 (-1750 2275)(-2075 2275);
FORCEPROP 0 LAST SIG_NAME XDP_CPU_TCK_BUF
J 0
(-2110 2285);
DISPLAY 0.617021 (-2110 2285);
PAINT ORANGE (-2110 2285);
FORCEPROP 2 LASTPROP $XRERR UNIQUE?
J 0
(-2350 2285);
DISPLAY 0.638298 (-2350 2285);
PAINT MONO (-2350 2285);
DISPLAY INVISIBLE (-2350 2285);
WIRE 16 -1 (-2075 2525)(-2075 2275);
WIRE 16 -1 (-2075 2275)(-2200 2275);
WIRE 16 -1 (-2075 2525)(-2075 2575);
WIRE 16 -1 (-2075 2525)(-2300 2525);
WIRE 16 -1 (-2300 2425)(-2300 2525);
WIRE 16 -1 (-2925 2775)(-2925 3075);
WIRE 16 -1 (-2000 3075)(-2925 3075);
WIRE 16 -1 (-3200 3075)(-2925 3075);
FORCEPROP 0 LAST SIG_NAME XDP_PCH_CPU_TCK0
J 0
(-3160 3085);
DISPLAY 0.617021 (-3160 3085);
PAINT ORANGE (-3160 3085);
WIRE 16 -1 (-2275 1425)(-1575 1425);
FORCEPROP 2 LAST SIG_NAME XDP_PRESENT_N
J 0
(-2260 1435);
DISPLAY 0.617021 (-2260 1435);
PAINT ORANGE (-2260 1435);
WIRE 16 -1 (-2200 500)(-1475 500);
FORCEPROP 2 LAST SIG_NAME XDP_ITP_PMODE
J 0
(-2160 510);
DISPLAY 0.617021 (-2160 510);
PAINT ORANGE (-2160 510);
WIRE 16 -1 (-2275 3700)(-2825 3700);
FORCEPROP 2 LAST SIG_NAME RST_RSMRST_N
J 2
(-2435 3710);
DISPLAY 0.617021 (-2435 3710);
PAINT ORANGE (-2435 3710);
WIRE 16 -1 (-2925 2275)(-2400 2275);
FORCEPROP 0 LAST SIG_NAME XDP_CPU_GTL_TCK_R2
J 0
(-2910 2285);
DISPLAY 0.617021 (-2910 2285);
PAINT ORANGE (-2910 2285);
FORCEPROP 2 LASTPROP $XRERR UNIQUE?
J 0
(-3150 2285);
DISPLAY 0.638298 (-3150 2285);
PAINT MONO (-3150 2285);
DISPLAY INVISIBLE (-3150 2285);
WIRE 16 -1 (-2925 2575)(-2925 2275);
DOT 1 (875 4500);
DOT 1 (875 4200);
DOT 1 (875 4350);
DOT 1 (3250 2150);
DOT 1 (2175 2600);
DOT 1 (2425 2150);
DOT 1 (3250 1700);
DOT 1 (2425 1700);
DOT 1 (2450 1125);
DOT 1 (1350 3500);
DOT 1 (875 4050);
DOT 1 (875 3900);
DOT 1 (875 3750);
DOT 1 (750 3600);
DOT 1 (875 3450);
DOT 1 (875 2775);
DOT 1 (-100 4350);
DOT 1 (-100 4200);
DOT 1 (-100 4050);
DOT 1 (-100 3900);
DOT 1 (-100 3750);
DOT 1 (0 3600);
DOT 1 (-100 3200);
DOT 1 (-100 3450);
DOT 1 (-625 3250);
DOT 1 (-100 2775);
DOT 1 (-1250 3075);
DOT 1 (-925 1425);
DOT 1 (-1850 1100);
DOT 1 (-2925 3075);
DOT 1 (-2075 2825);
DOT 1 (-2075 2525);
DOT 1 (-2075 2275);
FORCENOTE
(HOOK5)
(550 3664) 0;
DISPLAY LEFT (550 3664);
DISPLAY 0.936170 (550 3664);
PAINT PURPLE (550 3664);
FORCENOTE
(HOOK4)
(550 3714) 0;
DISPLAY LEFT (550 3714);
DISPLAY 0.936170 (550 3714);
PAINT PURPLE (550 3714);
FORCENOTE
(HOOK6)
(550 3564) 0;
DISPLAY LEFT (550 3564);
DISPLAY 0.936170 (550 3564);
PAINT PURPLE (550 3564);
FORCENOTE
(HOOK7)
(550 3514) 0;
DISPLAY LEFT (550 3514);
DISPLAY 0.936170 (550 3514);
PAINT PURPLE (550 3514);
FORCENOTE
(HOOK1)
(-475 3664) 0;
DISPLAY LEFT (-475 3664);
DISPLAY 0.936170 (-475 3664);
PAINT PURPLE (-475 3664);
FORCENOTE
(HOOK0)
(-475 3714) 0;
DISPLAY LEFT (-475 3714);
DISPLAY 0.936170 (-475 3714);
PAINT PURPLE (-475 3714);
FORCENOTE
(HOOK2)
(-450 3564) 0;
DISPLAY LEFT (-450 3564);
DISPLAY 0.936170 (-450 3564);
PAINT PURPLE (-450 3564);
FORCENOTE
(HOOK3)
(-450 3514) 0;
DISPLAY LEFT (-450 3514);
DISPLAY 0.936170 (-450 3514);
PAINT PURPLE (-450 3514);
FORCENOTE
ROOM=DEBUG
(-3652 579) 0;
DISPLAY LEFT (-3652 579);
PAINT PURPLE (-3652 579);
QUIT
